FILE_TYPE = MACRO_DRAWING;
SET COLOR_WIRE YELLOW;
SET COLOR_PROP MONO;
SET COLOR_DOT WHITE;
SET COLOR_ARC YELLOW;
SET COLOR_BODY GREEN;
SET COLOR_NOTE MONO;
SET PROP_DISPLAY VALUE;
SET PAGE_NUMBER P119;
FORCEADD OFFPAGE..4
R 2
(-7375 3650);
FORCEPROP 2 LAST $XR0 133 
J 0
(-7657 3650);
DISPLAY 0.638298 (-7657 3650);
PAINT MONO (-7657 3650);
FORCEPROP 1 LAST OFFPAGE TRUE
J 2
(-7700 3525);
DISPLAY 0.872340 (-7700 3525);
PAINT GREEN (-7700 3525);
DISPLAY INVISIBLE (-7700 3525);
FORCEPROP 1 LAST COMMENT_BODY TRUE
J 2
(-7350 3550);
DISPLAY 0.872340 (-7350 3550);
PAINT GREEN (-7350 3550);
DISPLAY INVISIBLE (-7350 3550);
FORCEPROP 2 LAST CDS_LIB mstr_standard
J 0
(-7375 3650);
PAINT ORANGE (-7375 3650);
DISPLAY INVISIBLE (-7375 3650);
FORCEPROP 2 LAST PATH I10
J 0
(-7325 3725);
DISPLAY 1.021277 (-7325 3725);
PAINT ORANGE (-7325 3725);
DISPLAY INVISIBLE (-7325 3725);
FORCEADD OFFPAGE..1
(-7375 4250);
FORCEPROP 2 LAST $XR0 168 
J 0
(-7627 4250);
DISPLAY 0.638298 (-7627 4250);
PAINT MONO (-7627 4250);
FORCEPROP 2 LAST $XR1 120 
J 0
(-7747 4250);
DISPLAY 0.638298 (-7747 4250);
PAINT MONO (-7747 4250);
FORCEPROP 2 LAST $XR2 147 
J 0
(-7867 4250);
DISPLAY 0.638298 (-7867 4250);
PAINT MONO (-7867 4250);
FORCEPROP 2 LAST CDS_LIB mstr_standard
J 0
(-7375 4250);
PAINT ORANGE (-7375 4250);
DISPLAY INVISIBLE (-7375 4250);
FORCEPROP 1 LAST COMMENT_BODY TRUE
J 0
(-7250 4150);
DISPLAY 0.872340 (-7250 4150);
PAINT GREEN (-7250 4150);
DISPLAY INVISIBLE (-7250 4150);
FORCEPROP 2 LAST PATH I100
J 0
(-7325 4325);
DISPLAY 1.021277 (-7325 4325);
PAINT ORANGE (-7325 4325);
DISPLAY INVISIBLE (-7325 4325);
FORCEPROP 1 LAST OFFPAGE TRUE
J 0
(-7050 4125);
DISPLAY 0.872340 (-7050 4125);
PAINT GREEN (-7050 4125);
DISPLAY INVISIBLE (-7050 4125);
FORCEADD OFFPAGE..1
(-7375 4300);
FORCEPROP 2 LAST $XR2 186 
J 0
(-7747 4300);
DISPLAY 0.638298 (-7747 4300);
PAINT MONO (-7747 4300);
FORCEPROP 2 LAST $XR0 133 
J 0
(-7627 4300);
DISPLAY 0.638298 (-7627 4300);
PAINT MONO (-7627 4300);
FORCEPROP 2 LAST $XR1 145 
J 0
(-7747 4300);
DISPLAY 0.638298 (-7747 4300);
PAINT MONO (-7747 4300);
FORCEPROP 2 LAST CDS_LIB mstr_standard
J 0
(-7375 4300);
PAINT ORANGE (-7375 4300);
DISPLAY INVISIBLE (-7375 4300);
FORCEPROP 1 LAST COMMENT_BODY TRUE
J 0
(-7250 4200);
DISPLAY 0.872340 (-7250 4200);
PAINT GREEN (-7250 4200);
DISPLAY INVISIBLE (-7250 4200);
FORCEPROP 2 LAST PATH I101
J 0
(-7325 4375);
DISPLAY 1.021277 (-7325 4375);
PAINT ORANGE (-7325 4375);
DISPLAY INVISIBLE (-7325 4375);
FORCEPROP 1 LAST OFFPAGE TRUE
J 0
(-7050 4175);
DISPLAY 0.872340 (-7050 4175);
PAINT GREEN (-7050 4175);
DISPLAY INVISIBLE (-7050 4175);
FORCEADD LBG_CORE_QAT_EXT_D..6
(-4200 3200);
FORCEPROP 1 LAST PART_NUMBER H91415-002
J 0
(-5950 1800);
DISPLAY 0.617021 (-5950 1800);
PAINT BLUE (-5950 1800);
FORCEPROP 2 LASTPIN (-6000 2000) $PN BL7
J 2
(-6010 2010);
DISPLAY 0.617021 (-6010 2010);
PAINT ORANGE (-6010 2010);
FORCEPROP 2 LASTPIN (-6000 2050) $PN BH9
J 2
(-6010 2060);
DISPLAY 0.617021 (-6010 2060);
PAINT ORANGE (-6010 2060);
FORCEPROP 2 LASTPIN (-6000 2100) $PN BN15
J 2
(-6010 2110);
DISPLAY 0.617021 (-6010 2110);
PAINT ORANGE (-6010 2110);
FORCEPROP 2 LASTPIN (-6000 2150) $PN BR9
J 2
(-6010 2160);
DISPLAY 0.617021 (-6010 2160);
PAINT ORANGE (-6010 2160);
FORCEPROP 2 LASTPIN (-6000 2200) $PN BN7
J 2
(-6010 2210);
DISPLAY 0.617021 (-6010 2210);
PAINT ORANGE (-6010 2210);
FORCEPROP 2 LASTPIN (-6000 2250) $PN BK17
J 2
(-6010 2260);
DISPLAY 0.617021 (-6010 2260);
PAINT ORANGE (-6010 2260);
FORCEPROP 2 LASTPIN (-6000 2500) $PN BL11
J 2
(-6010 2510);
DISPLAY 0.617021 (-6010 2510);
PAINT ORANGE (-6010 2510);
FORCEPROP 2 LASTPIN (-6000 2300) $PN BG18
J 2
(-6010 2310);
DISPLAY 0.617021 (-6010 2310);
PAINT ORANGE (-6010 2310);
FORCEPROP 2 LASTPIN (-6000 2350) $PN BR13
J 2
(-6010 2360);
DISPLAY 0.617021 (-6010 2360);
PAINT ORANGE (-6010 2360);
FORCEPROP 2 LASTPIN (-6000 2400) $PN BN11
J 2
(-6010 2410);
DISPLAY 0.617021 (-6010 2410);
PAINT ORANGE (-6010 2410);
FORCEPROP 2 LASTPIN (-6000 2450) $PN BH20
J 2
(-6010 2460);
DISPLAY 0.617021 (-6010 2460);
PAINT ORANGE (-6010 2460);
FORCEPROP 2 LASTPIN (-6000 2550) $PN BK9
J 2
(-6010 2560);
DISPLAY 0.617021 (-6010 2560);
PAINT ORANGE (-6010 2560);
FORCEPROP 2 LASTPIN (-6000 2600) $PN BL18
J 2
(-6010 2610);
DISPLAY 0.617021 (-6010 2610);
PAINT ORANGE (-6010 2610);
FORCEPROP 2 LASTPIN (-6000 2650) $PN BN18
J 2
(-6010 2660);
DISPLAY 0.617021 (-6010 2660);
PAINT ORANGE (-6010 2660);
FORCEPROP 2 LASTPIN (-6000 2750) $PN BK13
J 2
(-6010 2760);
DISPLAY 0.617021 (-6010 2760);
PAINT ORANGE (-6010 2760);
FORCEPROP 2 LASTPIN (-6000 2800) $PN BG22
J 2
(-6010 2810);
DISPLAY 0.617021 (-6010 2810);
PAINT ORANGE (-6010 2810);
FORCEPROP 2 LASTPIN (-6000 3000) $PN BJ22
J 2
(-6010 3010);
DISPLAY 0.617021 (-6010 3010);
PAINT ORANGE (-6010 3010);
FORCEPROP 2 LASTPIN (-6000 2950) $PN BK20
J 2
(-6010 2960);
DISPLAY 0.617021 (-6010 2960);
PAINT ORANGE (-6010 2960);
FORCEPROP 2 LASTPIN (-6000 2900) $PN BL15
J 2
(-6010 2910);
DISPLAY 0.617021 (-6010 2910);
PAINT ORANGE (-6010 2910);
FORCEPROP 2 LASTPIN (-6000 2850) $PN BG15
J 2
(-6010 2860);
DISPLAY 0.617021 (-6010 2860);
PAINT ORANGE (-6010 2860);
FORCEPROP 2 LASTPIN (-6000 3050) $PN BH17
J 2
(-6010 3060);
DISPLAY 0.617021 (-6010 3060);
PAINT ORANGE (-6010 3060);
FORCEPROP 2 LASTPIN (-6000 3150) $PN BM20
J 2
(-6010 3160);
DISPLAY 0.617021 (-6010 3160);
PAINT ORANGE (-6010 3160);
FORCEPROP 2 LASTPIN (-6000 3100) $PN BR17
J 2
(-6010 3110);
DISPLAY 0.617021 (-6010 3110);
PAINT ORANGE (-6010 3110);
FORCEPROP 2 LASTPIN (-6000 3250) $PN N3
J 2
(-6010 3260);
DISPLAY 0.617021 (-6010 3260);
PAINT ORANGE (-6010 3260);
FORCEPROP 2 LASTPIN (-6000 3300) $PN Y3
J 2
(-6010 3310);
DISPLAY 0.617021 (-6010 3310);
PAINT ORANGE (-6010 3310);
FORCEPROP 2 LASTPIN (-6000 3350) $PN N1
J 2
(-6010 3360);
DISPLAY 0.617021 (-6010 3360);
PAINT ORANGE (-6010 3360);
FORCEPROP 2 LASTPIN (-6000 3400) $PN W2
J 2
(-6010 3410);
DISPLAY 0.617021 (-6010 3410);
PAINT ORANGE (-6010 3410);
FORCEPROP 2 LASTPIN (-6000 3450) $PN Y1
J 2
(-6010 3460);
DISPLAY 0.617021 (-6010 3460);
PAINT ORANGE (-6010 3460);
FORCEPROP 2 LASTPIN (-6000 3500) $PN P4
J 2
(-6010 3510);
DISPLAY 0.617021 (-6010 3510);
PAINT ORANGE (-6010 3510);
FORCEPROP 2 LASTPIN (-6000 3550) $PN P2
J 2
(-6010 3560);
DISPLAY 0.617021 (-6010 3560);
PAINT ORANGE (-6010 3560);
FORCEPROP 2 LASTPIN (-6000 3750) $PN AA4
J 2
(-6010 3760);
DISPLAY 0.617021 (-6010 3760);
PAINT ORANGE (-6010 3760);
FORCEPROP 2 LASTPIN (-6000 3800) $PN AC2
J 2
(-6010 3810);
DISPLAY 0.617021 (-6010 3810);
PAINT ORANGE (-6010 3810);
FORCEPROP 2 LASTPIN (-6000 3600) $PN AA2
J 2
(-6010 3610);
DISPLAY 0.617021 (-6010 3610);
PAINT ORANGE (-6010 3610);
FORCEPROP 2 LASTPIN (-6000 3650) $PN AB1
J 2
(-6010 3660);
DISPLAY 0.617021 (-6010 3660);
PAINT ORANGE (-6010 3660);
FORCEPROP 2 LASTPIN (-6000 3700) $PN R3
J 2
(-6010 3710);
DISPLAY 0.617021 (-6010 3710);
PAINT ORANGE (-6010 3710);
FORCEPROP 2 LASTPIN (-6000 3850) $PN R1
J 2
(-6010 3860);
DISPLAY 0.617021 (-6010 3860);
PAINT ORANGE (-6010 3860);
FORCEPROP 2 LASTPIN (-6000 3900) $PN T4
J 2
(-6010 3910);
DISPLAY 0.617021 (-6010 3910);
PAINT ORANGE (-6010 3910);
FORCEPROP 2 LASTPIN (-6000 3950) $PN AB3
J 2
(-6010 3960);
DISPLAY 0.617021 (-6010 3960);
PAINT ORANGE (-6010 3960);
FORCEPROP 2 LASTPIN (-6000 4000) $PN AC4
J 2
(-6010 4010);
DISPLAY 0.617021 (-6010 4010);
PAINT ORANGE (-6010 4010);
FORCEPROP 2 LASTPIN (-6000 4050) $PN T2
J 2
(-6010 4060);
DISPLAY 0.617021 (-6010 4060);
PAINT ORANGE (-6010 4060);
FORCEPROP 2 LASTPIN (-6000 4100) $PN AD1
J 2
(-6010 4110);
DISPLAY 0.617021 (-6010 4110);
PAINT ORANGE (-6010 4110);
FORCEPROP 2 LASTPIN (-6000 4250) $PN W4
J 2
(-6010 4260);
DISPLAY 0.617021 (-6010 4260);
PAINT ORANGE (-6010 4260);
FORCEPROP 2 LASTPIN (-6000 4300) $PN AE2
J 2
(-6010 4310);
DISPLAY 0.617021 (-6010 4310);
PAINT ORANGE (-6010 4310);
FORCEPROP 2 LASTPIN (-6000 4150) $PN AD3
J 2
(-6010 4160);
DISPLAY 0.617021 (-6010 4160);
PAINT ORANGE (-6010 4160);
FORCEPROP 2 LASTPIN (-6000 4200) $PN V3
J 2
(-6010 4210);
DISPLAY 0.617021 (-6010 4210);
PAINT ORANGE (-6010 4210);
FORCEPROP 2 LASTPIN (-6000 4350) $PN AE4
J 2
(-6010 4360);
DISPLAY 0.617021 (-6010 4360);
PAINT ORANGE (-6010 4360);
FORCEPROP 2 LASTPIN (-6000 4400) $PN V1
J 2
(-6010 4410);
DISPLAY 0.617021 (-6010 4410);
PAINT ORANGE (-6010 4410);
FORCEPROP 1 LAST MATERIAL IC
J 0
(-5950 4600);
DISPLAY 0.617021 (-5950 4600);
PAINT SKYBLUE (-5950 4600);
FORCEPROP 1 LAST LOCATION U7C1
J 0
(-5650 4675);
DISPLAY 0.617021 (-5650 4675);
PAINT AQUA (-5650 4675);
FORCEPROP 2 LASTPIN (-2400 2000) $PN BR42
J 0
(-2390 2010);
DISPLAY 0.617021 (-2390 2010);
PAINT ORANGE (-2390 2010);
FORCEPROP 2 LASTPIN (-2400 2050) $PN BK46
J 0
(-2390 2060);
DISPLAY 0.617021 (-2390 2060);
PAINT ORANGE (-2390 2060);
FORCEPROP 2 LASTPIN (-2400 2500) $PN BV47
J 0
(-2390 2510);
DISPLAY 0.617021 (-2390 2510);
PAINT ORANGE (-2390 2510);
FORCEPROP 2 LASTPIN (-2400 2100) $PN BJ44
J 0
(-2390 2110);
DISPLAY 0.617021 (-2390 2110);
PAINT ORANGE (-2390 2110);
FORCEPROP 2 LASTPIN (-2400 2150) $PN BW45
J 0
(-2390 2160);
DISPLAY 0.617021 (-2390 2160);
PAINT ORANGE (-2390 2160);
FORCEPROP 2 LASTPIN (-2400 2200) $PN BM42
J 0
(-2390 2210);
DISPLAY 0.617021 (-2390 2210);
PAINT ORANGE (-2390 2210);
FORCEPROP 2 LASTPIN (-2400 2250) $PN BM38
J 0
(-2390 2260);
DISPLAY 0.617021 (-2390 2260);
PAINT ORANGE (-2390 2260);
FORCEPROP 2 LASTPIN (-2400 2300) $PN BW41
J 0
(-2390 2310);
DISPLAY 0.617021 (-2390 2310);
PAINT ORANGE (-2390 2310);
FORCEPROP 2 LASTPIN (-2400 2350) $PN CA45
J 0
(-2390 2360);
DISPLAY 0.617021 (-2390 2360);
PAINT ORANGE (-2390 2360);
FORCEPROP 2 LASTPIN (-2400 2400) $PN BR38
J 0
(-2390 2410);
DISPLAY 0.617021 (-2390 2410);
PAINT ORANGE (-2390 2410);
FORCEPROP 2 LASTPIN (-2400 2450) $PN BY42
J 0
(-2390 2460);
DISPLAY 0.617021 (-2390 2460);
PAINT ORANGE (-2390 2460);
FORCEPROP 2 LASTPIN (-2400 2550) $PN BY47
J 0
(-2390 2560);
DISPLAY 0.617021 (-2390 2560);
PAINT ORANGE (-2390 2560);
FORCEPROP 2 LASTPIN (-2400 2600) $PN BN40
J 0
(-2390 2610);
DISPLAY 0.617021 (-2390 2610);
PAINT ORANGE (-2390 2610);
FORCEPROP 2 LASTPIN (-2400 2650) $PN BY44
J 0
(-2390 2660);
DISPLAY 0.617021 (-2390 2660);
PAINT ORANGE (-2390 2660);
FORCEPROP 2 LASTPIN (-2400 2700) $PN BL44
J 0
(-2390 2710);
DISPLAY 0.617021 (-2390 2710);
PAINT ORANGE (-2390 2710);
FORCEPROP 2 LASTPIN (-2400 2750) $PN BW43
J 0
(-2390 2760);
DISPLAY 0.617021 (-2390 2760);
PAINT ORANGE (-2390 2760);
FORCEPROP 2 LASTPIN (-2400 2800) $PN BV42
J 0
(-2390 2810);
DISPLAY 0.617021 (-2390 2810);
PAINT ORANGE (-2390 2810);
FORCEPROP 2 LASTPIN (-2400 2850) $PN BW48
J 0
(-2390 2860);
DISPLAY 0.617021 (-2390 2860);
PAINT ORANGE (-2390 2860);
FORCEPROP 2 LASTPIN (-2400 2900) $PN CA41
J 0
(-2390 2910);
DISPLAY 0.617021 (-2390 2910);
PAINT ORANGE (-2390 2910);
FORCEPROP 2 LASTPIN (-2400 2950) $PN CA43
J 0
(-2390 2960);
DISPLAY 0.617021 (-2390 2960);
PAINT ORANGE (-2390 2960);
FORCEPROP 2 LASTPIN (-2400 3050) $PN BV44
J 0
(-2390 3060);
DISPLAY 0.617021 (-2390 3060);
PAINT ORANGE (-2390 3060);
FORCEPROP 2 LASTPIN (-2400 3250) $PN BW28
J 0
(-2390 3260);
DISPLAY 0.617021 (-2390 3260);
PAINT ORANGE (-2390 3260);
FORCEPROP 2 LASTPIN (-2400 3300) $PN BV27
J 0
(-2390 3310);
DISPLAY 0.617021 (-2390 3310);
PAINT ORANGE (-2390 3310);
FORCEPROP 2 LASTPIN (-2400 3350) $PN BY27
J 0
(-2390 3360);
DISPLAY 0.617021 (-2390 3360);
PAINT ORANGE (-2390 3360);
FORCEPROP 2 LASTPIN (-2400 3400) $PN BV29
J 0
(-2390 3410);
DISPLAY 0.617021 (-2390 3410);
PAINT ORANGE (-2390 3410);
FORCEPROP 2 LASTPIN (-2400 3450) $PN BW30
J 0
(-2390 3460);
DISPLAY 0.617021 (-2390 3460);
PAINT ORANGE (-2390 3460);
FORCEPROP 2 LASTPIN (-2400 3500) $PN BW34
J 0
(-2390 3510);
DISPLAY 0.617021 (-2390 3510);
PAINT ORANGE (-2390 3510);
FORCEPROP 2 LASTPIN (-2400 3100) $PN BR46
J 0
(-2390 3110);
DISPLAY 0.617021 (-2390 3110);
PAINT ORANGE (-2390 3110);
FORCEPROP 2 LASTPIN (-2400 3150) $PN BN44
J 0
(-2390 3160);
DISPLAY 0.617021 (-2390 3160);
PAINT ORANGE (-2390 3160);
FORCEPROP 2 LASTPIN (-2400 3550) $PN CA28
J 0
(-2390 3560);
DISPLAY 0.617021 (-2390 3560);
PAINT ORANGE (-2390 3560);
FORCEPROP 2 LASTPIN (-2400 3750) $PN BV31
J 0
(-2390 3760);
DISPLAY 0.617021 (-2390 3760);
PAINT ORANGE (-2390 3760);
FORCEPROP 2 LASTPIN (-2400 3800) $PN BV33
J 0
(-2390 3810);
DISPLAY 0.617021 (-2390 3810);
PAINT ORANGE (-2390 3810);
FORCEPROP 2 LASTPIN (-2400 3850) $PN CA30
J 0
(-2390 3860);
DISPLAY 0.617021 (-2390 3860);
PAINT ORANGE (-2390 3860);
FORCEPROP 2 LASTPIN (-2400 3900) $PN BV38
J 0
(-2390 3910);
DISPLAY 0.617021 (-2390 3910);
PAINT ORANGE (-2390 3910);
FORCEPROP 2 LASTPIN (-2400 3950) $PN BY38
J 0
(-2390 3960);
DISPLAY 0.617021 (-2390 3960);
PAINT ORANGE (-2390 3960);
FORCEPROP 2 LASTPIN (-2400 4000) $PN CA32
J 0
(-2390 4010);
DISPLAY 0.617021 (-2390 4010);
PAINT ORANGE (-2390 4010);
FORCEPROP 2 LASTPIN (-2400 4050) $PN BW37
J 0
(-2390 4060);
DISPLAY 0.617021 (-2390 4060);
PAINT ORANGE (-2390 4060);
FORCEPROP 2 LASTPIN (-2400 3600) $PN BV35
J 0
(-2390 3610);
DISPLAY 0.617021 (-2390 3610);
PAINT ORANGE (-2390 3610);
FORCEPROP 2 LASTPIN (-2400 3650) $PN BW32
J 0
(-2390 3660);
DISPLAY 0.617021 (-2390 3660);
PAINT ORANGE (-2390 3660);
FORCEPROP 2 LASTPIN (-2400 3700) $PN BY29
J 0
(-2390 3710);
DISPLAY 0.617021 (-2390 3710);
PAINT ORANGE (-2390 3710);
FORCEPROP 2 LASTPIN (-2400 4100) $PN BY31
J 0
(-2390 4110);
DISPLAY 0.617021 (-2390 4110);
PAINT ORANGE (-2390 4110);
FORCEPROP 2 LASTPIN (-2400 4150) $PN BY35
J 0
(-2390 4160);
DISPLAY 0.617021 (-2390 4160);
PAINT ORANGE (-2390 4160);
FORCEPROP 2 LASTPIN (-2400 4200) $PN BW39
J 0
(-2390 4210);
DISPLAY 0.617021 (-2390 4210);
PAINT ORANGE (-2390 4210);
FORCEPROP 2 LASTPIN (-2400 4250) $PN CA39
J 0
(-2390 4260);
DISPLAY 0.617021 (-2390 4260);
PAINT ORANGE (-2390 4260);
FORCEPROP 2 LASTPIN (-2400 4300) $PN BY33
J 0
(-2390 4310);
DISPLAY 0.617021 (-2390 4310);
PAINT ORANGE (-2390 4310);
FORCEPROP 2 LASTPIN (-2400 4350) $PN CA34
J 0
(-2390 4360);
DISPLAY 0.617021 (-2390 4360);
PAINT ORANGE (-2390 4360);
FORCEPROP 2 LASTPIN (-2400 4400) $PN CA37
J 0
(-2390 4410);
DISPLAY 0.617021 (-2390 4410);
PAINT ORANGE (-2390 4410);
FORCEPROP 2 LASTPIN (-2400 3000) $PN CA48
J 0
(-2390 3010);
DISPLAY 0.617021 (-2390 3010);
PAINT ORANGE (-2390 3010);
FORCEPROP 2 LASTPIN (-6000 2700) $PN BH13
J 2
(-6010 2710);
DISPLAY 0.617021 (-6010 2710);
PAINT ORANGE (-6010 2710);
FORCEPROP 2 LAST CDS_LIB mstr_u_proc
J 0
(-4200 3200);
PAINT ORANGE (-4200 3200);
DISPLAY INVISIBLE (-4200 3200);
FORCEPROP 2 LAST SEC 6
J 0
(-5650 4725);
DISPLAY 0.680851 (-5650 4725);
PAINT MONO (-5650 4725);
DISPLAY INVISIBLE (-5650 4725);
FORCEPROP 2 LAST CDS_LOCATION U7C1
J 0
(-5650 4675);
DISPLAY 0.617021 (-5650 4675);
PAINT AQUA (-5650 4675);
DISPLAY INVISIBLE (-5650 4675);
FORCEPROP 1 LAST PACK_TYPE BGA1
J 0
(-5950 4700);
PAINT SKYBLUE (-5950 4700);
DISPLAY INVISIBLE (-5950 4700);
FORCEPROP 2 LAST SEC_TYPE BGA1
J 0
(-5650 4725);
DISPLAY 1.021277 (-5650 4725);
PAINT ORANGE (-5650 4725);
DISPLAY INVISIBLE (-5650 4725);
FORCEPROP 0 LAST BOM_COST SB
J 0
(-5700 5375);
DISPLAY 1.361702 (-5700 5375);
PAINT ORANGE (-5700 5375);
DISPLAY INVISIBLE (-5700 5375);
FORCEPROP 0 LAST ROOM SB
J 0
(-5700 5275);
DISPLAY 1.361702 (-5700 5275);
PAINT ORANGE (-5700 5275);
DISPLAY INVISIBLE (-5700 5275);
FORCEPROP 1 LAST PATH I115
J 0
(-4200 4600);
PAINT GREEN (-4200 4600);
DISPLAY INVISIBLE (-4200 4600);
FORCEADD OFFPAGE..2
(-775 2950);
FORCEPROP 2 LAST $XR0 190 
J 0
(-586 2950);
DISPLAY 0.638298 (-586 2950);
PAINT MONO (-586 2950);
FORCEPROP 1 LAST COMMENT_BODY TRUE
J 0
(-820 2855);
DISPLAY 0.872340 (-820 2855);
PAINT GREEN (-820 2855);
DISPLAY INVISIBLE (-820 2855);
FORCEPROP 2 LAST CDS_LIB mstr_standard
J 0
(-775 2950);
PAINT ORANGE (-775 2950);
DISPLAY INVISIBLE (-775 2950);
FORCEPROP 2 LAST PATH I119
J 0
(-600 3025);
DISPLAY 1.021277 (-600 3025);
PAINT ORANGE (-600 3025);
DISPLAY INVISIBLE (-600 3025);
FORCEPROP 1 LAST OFFPAGE TRUE
J 0
(-450 2825);
DISPLAY 0.872340 (-450 2825);
PAINT GREEN (-450 2825);
DISPLAY INVISIBLE (-450 2825);
FORCEADD TAP..6
(-6975 3300);
FORCEPROP 1 LASTPIN (-6925 3300) BN 0
J 0
(-6977 3308);
DISPLAY 0.617021 (-6977 3308);
PAINT GREEN (-6977 3308);
FORCEPROP 1 LAST BODY_TYPE PLUMBING
J 0
(-6975 3250);
DISPLAY 0.872340 (-6975 3250);
PAINT GREEN (-6975 3250);
DISPLAY INVISIBLE (-6975 3250);
FORCEPROP 2 LAST CDS_LIB mstr_standard
J 0
(-6975 3300);
PAINT ORANGE (-6975 3300);
DISPLAY INVISIBLE (-6975 3300);
FORCEPROP 1 LAST PATH I120
J 0
(-6977 3300);
DISPLAY 0.872340 (-6977 3300);
PAINT GREEN (-6977 3300);
DISPLAY INVISIBLE (-6977 3300);
FORCEPROP 1 LAST HDL_TAP TRUE
J 0
(-6650 3175);
DISPLAY 0.872340 (-6650 3175);
PAINT ORANGE (-6650 3175);
DISPLAY INVISIBLE (-6650 3175);
FORCEADD TAP..6
(-6975 3350);
FORCEPROP 1 LASTPIN (-6925 3350) BN 1
J 0
(-6977 3358);
DISPLAY 0.617021 (-6977 3358);
PAINT GREEN (-6977 3358);
FORCEPROP 1 LAST BODY_TYPE PLUMBING
J 0
(-6975 3300);
DISPLAY 0.872340 (-6975 3300);
PAINT GREEN (-6975 3300);
DISPLAY INVISIBLE (-6975 3300);
FORCEPROP 1 LAST PATH I121
J 0
(-6977 3350);
DISPLAY 0.872340 (-6977 3350);
PAINT GREEN (-6977 3350);
DISPLAY INVISIBLE (-6977 3350);
FORCEPROP 2 LAST CDS_LIB mstr_standard
J 0
(-6975 3350);
PAINT ORANGE (-6975 3350);
DISPLAY INVISIBLE (-6975 3350);
FORCEPROP 1 LAST HDL_TAP TRUE
J 0
(-6650 3225);
DISPLAY 0.872340 (-6650 3225);
PAINT ORANGE (-6650 3225);
DISPLAY INVISIBLE (-6650 3225);
FORCEADD TAP..6
(-6975 3400);
FORCEPROP 1 LASTPIN (-6925 3400) BN 2
J 0
(-6977 3408);
DISPLAY 0.617021 (-6977 3408);
PAINT GREEN (-6977 3408);
FORCEPROP 1 LAST PATH I122
J 0
(-6977 3400);
DISPLAY 0.872340 (-6977 3400);
PAINT GREEN (-6977 3400);
DISPLAY INVISIBLE (-6977 3400);
FORCEPROP 1 LAST BODY_TYPE PLUMBING
J 0
(-6975 3350);
DISPLAY 0.872340 (-6975 3350);
PAINT GREEN (-6975 3350);
DISPLAY INVISIBLE (-6975 3350);
FORCEPROP 2 LAST CDS_LIB mstr_standard
J 0
(-6975 3400);
PAINT ORANGE (-6975 3400);
DISPLAY INVISIBLE (-6975 3400);
FORCEPROP 1 LAST HDL_TAP TRUE
J 0
(-6650 3275);
DISPLAY 0.872340 (-6650 3275);
PAINT ORANGE (-6650 3275);
DISPLAY INVISIBLE (-6650 3275);
FORCEADD TAP..6
(-6975 3450);
FORCEPROP 1 LASTPIN (-6925 3450) BN 3
J 0
(-6977 3458);
DISPLAY 0.617021 (-6977 3458);
PAINT GREEN (-6977 3458);
FORCEPROP 1 LAST BODY_TYPE PLUMBING
J 0
(-6975 3400);
DISPLAY 0.872340 (-6975 3400);
PAINT GREEN (-6975 3400);
DISPLAY INVISIBLE (-6975 3400);
FORCEPROP 2 LAST CDS_LIB mstr_standard
J 0
(-6975 3450);
PAINT ORANGE (-6975 3450);
DISPLAY INVISIBLE (-6975 3450);
FORCEPROP 1 LAST PATH I123
J 0
(-6977 3450);
DISPLAY 0.872340 (-6977 3450);
PAINT GREEN (-6977 3450);
DISPLAY INVISIBLE (-6977 3450);
FORCEPROP 1 LAST HDL_TAP TRUE
J 0
(-6650 3325);
DISPLAY 0.872340 (-6650 3325);
PAINT ORANGE (-6650 3325);
DISPLAY INVISIBLE (-6650 3325);
FORCEADD OFFPAGE..6
(-7375 3475);
FORCEPROP 2 LAST $XR0 146 
J 0
(-7685 3475);
DISPLAY 0.638298 (-7685 3475);
PAINT MONO (-7685 3475);
FORCEPROP 2 LAST CDS_LIB mstr_standard
J 0
(-7375 3475);
PAINT ORANGE (-7375 3475);
DISPLAY INVISIBLE (-7375 3475);
FORCEPROP 1 LAST COMMENT_BODY TRUE
J 0
(-7275 3400);
DISPLAY 0.872340 (-7275 3400);
PAINT GREEN (-7275 3400);
DISPLAY INVISIBLE (-7275 3400);
FORCEPROP 2 LAST PATH I124
J 0
(-7325 3550);
DISPLAY 1.021277 (-7325 3550);
PAINT ORANGE (-7325 3550);
DISPLAY INVISIBLE (-7325 3550);
FORCEPROP 1 LAST OFFPAGE TRUE
J 0
(-7050 3350);
DISPLAY 0.872340 (-7050 3350);
PAINT GREEN (-7050 3350);
DISPLAY INVISIBLE (-7050 3350);
FORCEADD OFFPAGE..1
(-7375 4400);
FORCEPROP 2 LAST $XR0 120 
J 0
(-7627 4400);
DISPLAY 0.638298 (-7627 4400);
PAINT MONO (-7627 4400);
FORCEPROP 2 LAST $XR1 133 
J 0
(-7747 4400);
DISPLAY 0.638298 (-7747 4400);
PAINT MONO (-7747 4400);
FORCEPROP 2 LAST $XR2 146 
J 0
(-7867 4400);
DISPLAY 0.638298 (-7867 4400);
PAINT MONO (-7867 4400);
FORCEPROP 2 LAST $XR3 182 
J 0
(-7987 4400);
DISPLAY 0.638298 (-7987 4400);
PAINT MONO (-7987 4400);
FORCEPROP 1 LAST COMMENT_BODY TRUE
J 0
(-7250 4300);
DISPLAY 0.872340 (-7250 4300);
PAINT GREEN (-7250 4300);
DISPLAY INVISIBLE (-7250 4300);
FORCEPROP 2 LAST CDS_LIB mstr_standard
J 0
(-7375 4400);
PAINT ORANGE (-7375 4400);
DISPLAY INVISIBLE (-7375 4400);
FORCEPROP 2 LAST PATH I125
J 0
(-7325 4475);
DISPLAY 1.021277 (-7325 4475);
PAINT ORANGE (-7325 4475);
DISPLAY INVISIBLE (-7325 4475);
FORCEPROP 1 LAST OFFPAGE TRUE
J 0
(-7050 4275);
DISPLAY 0.872340 (-7050 4275);
PAINT GREEN (-7050 4275);
DISPLAY INVISIBLE (-7050 4275);
FORCEADD OFFPAGE..4
R 2
(-7375 3950);
FORCEPROP 2 LAST $XR0 181 
J 0
(-7627 3950);
DISPLAY 0.638298 (-7627 3950);
PAINT MONO (-7627 3950);
FORCEPROP 2 LAST $XR1 145 
J 0
(-7747 3950);
DISPLAY 0.638298 (-7747 3950);
PAINT MONO (-7747 3950);
FORCEPROP 1 LAST OFFPAGE TRUE
J 2
(-7700 3825);
DISPLAY 0.872340 (-7700 3825);
PAINT GREEN (-7700 3825);
DISPLAY INVISIBLE (-7700 3825);
FORCEPROP 1 LAST COMMENT_BODY TRUE
J 2
(-7350 3850);
DISPLAY 0.872340 (-7350 3850);
PAINT GREEN (-7350 3850);
DISPLAY INVISIBLE (-7350 3850);
FORCEPROP 2 LAST CDS_LIB mstr_standard
J 0
(-7375 3950);
PAINT ORANGE (-7375 3950);
DISPLAY INVISIBLE (-7375 3950);
FORCEPROP 2 LAST PATH I127
J 0
(-7325 4025);
DISPLAY 1.021277 (-7325 4025);
PAINT ORANGE (-7325 4025);
DISPLAY INVISIBLE (-7325 4025);
FORCEADD OFFPAGE..4
R 2
(-7375 4000);
FORCEPROP 2 LAST $XR0 181 
J 0
(-7627 4000);
DISPLAY 0.638298 (-7627 4000);
PAINT MONO (-7627 4000);
FORCEPROP 2 LAST $XR1 145 
J 0
(-7747 4000);
DISPLAY 0.638298 (-7747 4000);
PAINT MONO (-7747 4000);
FORCEPROP 1 LAST OFFPAGE TRUE
J 2
(-7700 3875);
DISPLAY 0.872340 (-7700 3875);
PAINT GREEN (-7700 3875);
DISPLAY INVISIBLE (-7700 3875);
FORCEPROP 1 LAST COMMENT_BODY TRUE
J 2
(-7350 3900);
DISPLAY 0.872340 (-7350 3900);
PAINT GREEN (-7350 3900);
DISPLAY INVISIBLE (-7350 3900);
FORCEPROP 2 LAST CDS_LIB mstr_standard
J 0
(-7375 4000);
PAINT ORANGE (-7375 4000);
DISPLAY INVISIBLE (-7375 4000);
FORCEPROP 2 LAST PATH I128
J 0
(-7325 4075);
DISPLAY 1.021277 (-7325 4075);
PAINT ORANGE (-7325 4075);
DISPLAY INVISIBLE (-7325 4075);
FORCEADD OFFPAGE..4
R 2
(-7375 3900);
FORCEPROP 2 LAST $XR0 181 
J 0
(-7627 3900);
DISPLAY 0.638298 (-7627 3900);
PAINT MONO (-7627 3900);
FORCEPROP 2 LAST $XR1 145 
J 0
(-7747 3900);
DISPLAY 0.638298 (-7747 3900);
PAINT MONO (-7747 3900);
FORCEPROP 1 LAST OFFPAGE TRUE
J 2
(-7700 3775);
DISPLAY 0.872340 (-7700 3775);
PAINT GREEN (-7700 3775);
DISPLAY INVISIBLE (-7700 3775);
FORCEPROP 1 LAST COMMENT_BODY TRUE
J 2
(-7350 3800);
DISPLAY 0.872340 (-7350 3800);
PAINT GREEN (-7350 3800);
DISPLAY INVISIBLE (-7350 3800);
FORCEPROP 2 LAST CDS_LIB mstr_standard
J 0
(-7375 3900);
PAINT ORANGE (-7375 3900);
DISPLAY INVISIBLE (-7375 3900);
FORCEPROP 2 LAST PATH I129
J 0
(-7325 3975);
DISPLAY 1.021277 (-7325 3975);
PAINT ORANGE (-7325 3975);
DISPLAY INVISIBLE (-7325 3975);
FORCEADD OFFPAGE..4
R 2
(-7375 3800);
FORCEPROP 2 LAST $XR0 133 
J 0
(-7627 3800);
DISPLAY 0.638298 (-7627 3800);
PAINT MONO (-7627 3800);
FORCEPROP 1 LAST OFFPAGE TRUE
J 2
(-7700 3675);
DISPLAY 0.872340 (-7700 3675);
PAINT GREEN (-7700 3675);
DISPLAY INVISIBLE (-7700 3675);
FORCEPROP 1 LAST COMMENT_BODY TRUE
J 2
(-7350 3700);
DISPLAY 0.872340 (-7350 3700);
PAINT GREEN (-7350 3700);
DISPLAY INVISIBLE (-7350 3700);
FORCEPROP 2 LAST CDS_LIB mstr_standard
J 0
(-7375 3800);
PAINT ORANGE (-7375 3800);
DISPLAY INVISIBLE (-7375 3800);
FORCEPROP 2 LAST PATH I13
J 0
(-7325 3875);
DISPLAY 1.021277 (-7325 3875);
PAINT ORANGE (-7325 3875);
DISPLAY INVISIBLE (-7325 3875);
FORCEADD OFFPAGE..5
(-7175 2550);
FORCEPROP 2 LAST $XR0 119 
J 0
(-7460 2550);
DISPLAY 0.638298 (-7460 2550);
PAINT MONO (-7460 2550);
FORCEPROP 2 LAST $XR1 145 
J 0
(-7580 2550);
DISPLAY 0.638298 (-7580 2550);
PAINT MONO (-7580 2550);
FORCEPROP 2 LAST $XR2 170 
J 0
(-7700 2550);
DISPLAY 0.638298 (-7700 2550);
PAINT MONO (-7700 2550);
FORCEPROP 2 LAST CDS_LIB mstr_standard
J 0
(-7175 2550);
PAINT ORANGE (-7175 2550);
DISPLAY INVISIBLE (-7175 2550);
FORCEPROP 1 LAST COMMENT_BODY TRUE
J 0
(-7075 2475);
DISPLAY 1.404255 (-7075 2475);
PAINT PEACH (-7075 2475);
DISPLAY INVISIBLE (-7075 2475);
FORCEPROP 1 LAST OFFPAGE TRUE
J 0
(-6850 2425);
PAINT GREEN (-6850 2425);
DISPLAY INVISIBLE (-6850 2425);
FORCEPROP 2 LAST PATH I130
J 0
(-7125 2625);
DISPLAY 1.021277 (-7125 2625);
PAINT ORANGE (-7125 2625);
DISPLAY INVISIBLE (-7125 2625);
FORCEADD OFFPAGE..4
R 2
(-7175 2250);
FORCEPROP 2 LAST $XR0 218 
J 0
(-7427 2250);
DISPLAY 0.638298 (-7427 2250);
PAINT MONO (-7427 2250);
FORCEPROP 2 LAST $XR1 94 
J 0
(-7517 2250);
DISPLAY 0.638298 (-7517 2250);
PAINT MONO (-7517 2250);
FORCEPROP 2 LAST $XR2 144 
J 0
(-7637 2250);
DISPLAY 0.638298 (-7637 2250);
PAINT MONO (-7637 2250);
FORCEPROP 1 LAST OFFPAGE TRUE
J 2
(-7500 2125);
DISPLAY 0.872340 (-7500 2125);
PAINT GREEN (-7500 2125);
DISPLAY INVISIBLE (-7500 2125);
FORCEPROP 2 LAST CDS_LIB mstr_standard
J 0
(-7175 2250);
PAINT ORANGE (-7175 2250);
DISPLAY INVISIBLE (-7175 2250);
FORCEPROP 1 LAST COMMENT_BODY TRUE
J 2
(-7150 2150);
DISPLAY 0.872340 (-7150 2150);
PAINT GREEN (-7150 2150);
DISPLAY INVISIBLE (-7150 2150);
FORCEPROP 2 LAST PATH I131
J 0
(-7125 2325);
DISPLAY 1.021277 (-7125 2325);
PAINT ORANGE (-7125 2325);
DISPLAY INVISIBLE (-7125 2325);
FORCEADD OFFPAGE..4
R 2
(-7175 2200);
FORCEPROP 2 LAST $XR0 215 
J 0
(-7427 2200);
DISPLAY 0.638298 (-7427 2200);
PAINT MONO (-7427 2200);
FORCEPROP 2 LAST $XR1 94 
J 0
(-7517 2200);
DISPLAY 0.638298 (-7517 2200);
PAINT MONO (-7517 2200);
FORCEPROP 2 LAST $XR2 145 
J 0
(-7637 2200);
DISPLAY 0.638298 (-7637 2200);
PAINT MONO (-7637 2200);
FORCEPROP 1 LAST OFFPAGE TRUE
J 2
(-7500 2075);
DISPLAY 0.872340 (-7500 2075);
PAINT GREEN (-7500 2075);
DISPLAY INVISIBLE (-7500 2075);
FORCEPROP 2 LAST CDS_LIB mstr_standard
J 0
(-7175 2200);
PAINT ORANGE (-7175 2200);
DISPLAY INVISIBLE (-7175 2200);
FORCEPROP 1 LAST COMMENT_BODY TRUE
J 2
(-7150 2100);
DISPLAY 0.872340 (-7150 2100);
PAINT GREEN (-7150 2100);
DISPLAY INVISIBLE (-7150 2100);
FORCEPROP 2 LAST PATH I132
J 0
(-7125 2275);
DISPLAY 1.021277 (-7125 2275);
PAINT ORANGE (-7125 2275);
DISPLAY INVISIBLE (-7125 2275);
FORCEADD OFFPAGE..1
(-7175 2350);
FORCEPROP 2 LAST $XR0 226 
J 0
(-7427 2350);
DISPLAY 0.638298 (-7427 2350);
PAINT MONO (-7427 2350);
FORCEPROP 2 LAST $XR1 94 
J 0
(-7517 2350);
DISPLAY 0.638298 (-7517 2350);
PAINT MONO (-7517 2350);
FORCEPROP 2 LAST $XR2 145 
J 0
(-7637 2350);
DISPLAY 0.638298 (-7637 2350);
PAINT MONO (-7637 2350);
FORCEPROP 2 LAST CDS_LIB mstr_standard
J 0
(-7175 2350);
PAINT ORANGE (-7175 2350);
DISPLAY INVISIBLE (-7175 2350);
FORCEPROP 1 LAST COMMENT_BODY TRUE
J 0
(-7050 2250);
DISPLAY 0.872340 (-7050 2250);
PAINT GREEN (-7050 2250);
DISPLAY INVISIBLE (-7050 2250);
FORCEPROP 2 LAST PATH I136
J 0
(-7125 2425);
DISPLAY 1.021277 (-7125 2425);
PAINT ORANGE (-7125 2425);
DISPLAY INVISIBLE (-7125 2425);
FORCEPROP 1 LAST OFFPAGE TRUE
J 0
(-6850 2225);
DISPLAY 0.872340 (-6850 2225);
PAINT GREEN (-6850 2225);
DISPLAY INVISIBLE (-6850 2225);
FORCEADD OFFPAGE..4
R 2
(-7175 2300);
FORCEPROP 2 LAST $XR0 223 
J 0
(-7427 2300);
DISPLAY 0.638298 (-7427 2300);
PAINT MONO (-7427 2300);
FORCEPROP 2 LAST $XR1 94 
J 0
(-7517 2300);
DISPLAY 0.638298 (-7517 2300);
PAINT MONO (-7517 2300);
FORCEPROP 2 LAST $XR2 144 
J 0
(-7637 2300);
DISPLAY 0.638298 (-7637 2300);
PAINT MONO (-7637 2300);
FORCEPROP 1 LAST OFFPAGE TRUE
J 2
(-7500 2175);
DISPLAY 0.872340 (-7500 2175);
PAINT GREEN (-7500 2175);
DISPLAY INVISIBLE (-7500 2175);
FORCEPROP 2 LAST CDS_LIB mstr_standard
J 0
(-7175 2300);
PAINT ORANGE (-7175 2300);
DISPLAY INVISIBLE (-7175 2300);
FORCEPROP 1 LAST COMMENT_BODY TRUE
J 2
(-7150 2200);
DISPLAY 0.872340 (-7150 2200);
PAINT GREEN (-7150 2200);
DISPLAY INVISIBLE (-7150 2200);
FORCEPROP 2 LAST PATH I137
J 0
(-7125 2375);
DISPLAY 1.021277 (-7125 2375);
PAINT ORANGE (-7125 2375);
DISPLAY INVISIBLE (-7125 2375);
FORCEADD OFFPAGE..5
(-7175 2950);
FORCEPROP 2 LAST $XR0 147 
J 0
(-7460 2950);
DISPLAY 0.638298 (-7460 2950);
PAINT MONO (-7460 2950);
FORCEPROP 2 LAST CDS_LIB mstr_standard
J 0
(-7175 2950);
PAINT ORANGE (-7175 2950);
DISPLAY INVISIBLE (-7175 2950);
FORCEPROP 1 LAST COMMENT_BODY TRUE
J 0
(-7075 2875);
DISPLAY 1.404255 (-7075 2875);
PAINT PEACH (-7075 2875);
DISPLAY INVISIBLE (-7075 2875);
FORCEPROP 2 LAST PATH I139
J 0
(-7125 3025);
DISPLAY 1.021277 (-7125 3025);
PAINT ORANGE (-7125 3025);
DISPLAY INVISIBLE (-7125 3025);
FORCEPROP 1 LAST OFFPAGE TRUE
J 0
(-6850 2825);
PAINT GREEN (-6850 2825);
DISPLAY INVISIBLE (-6850 2825);
FORCEPROP 2 LAST $XRERR ?
J 0
(-7574 2950);
DISPLAY 0.638298 (-7574 2950);
PAINT MONO (-7574 2950);
DISPLAY INVISIBLE (-7574 2950);
FORCEADD OFFPAGE..4
R 2
(-7375 3850);
FORCEPROP 2 LAST $XR0 133 
J 0
(-7627 3850);
DISPLAY 0.638298 (-7627 3850);
PAINT MONO (-7627 3850);
FORCEPROP 1 LAST OFFPAGE TRUE
J 2
(-7700 3725);
DISPLAY 0.872340 (-7700 3725);
PAINT GREEN (-7700 3725);
DISPLAY INVISIBLE (-7700 3725);
FORCEPROP 1 LAST COMMENT_BODY TRUE
J 2
(-7350 3750);
DISPLAY 0.872340 (-7350 3750);
PAINT GREEN (-7350 3750);
DISPLAY INVISIBLE (-7350 3750);
FORCEPROP 2 LAST CDS_LIB mstr_standard
J 0
(-7375 3850);
PAINT ORANGE (-7375 3850);
DISPLAY INVISIBLE (-7375 3850);
FORCEPROP 2 LAST PATH I14
J 0
(-7325 3925);
DISPLAY 1.021277 (-7325 3925);
PAINT ORANGE (-7325 3925);
DISPLAY INVISIBLE (-7325 3925);
FORCEADD OFFPAGE..5
(-7175 3050);
FORCEPROP 2 LAST $XR0 144 
J 0
(-7460 3050);
DISPLAY 0.638298 (-7460 3050);
PAINT MONO (-7460 3050);
FORCEPROP 2 LAST $XR1 170 
J 0
(-7580 3050);
DISPLAY 0.638298 (-7580 3050);
PAINT MONO (-7580 3050);
FORCEPROP 2 LAST CDS_LIB mstr_standard
J 0
(-7175 3050);
PAINT ORANGE (-7175 3050);
DISPLAY INVISIBLE (-7175 3050);
FORCEPROP 1 LAST COMMENT_BODY TRUE
J 0
(-7075 2975);
DISPLAY 1.404255 (-7075 2975);
PAINT PEACH (-7075 2975);
DISPLAY INVISIBLE (-7075 2975);
FORCEPROP 1 LAST OFFPAGE TRUE
J 0
(-6850 2925);
PAINT GREEN (-6850 2925);
DISPLAY INVISIBLE (-6850 2925);
FORCEPROP 2 LAST PATH I140
J 0
(-7125 3125);
DISPLAY 1.021277 (-7125 3125);
PAINT ORANGE (-7125 3125);
DISPLAY INVISIBLE (-7125 3125);
FORCEADD OFFPAGE..4
(-775 3800);
FORCEPROP 2 LAST $XR0 164 
J 0
(-589 3800);
DISPLAY 0.638298 (-589 3800);
PAINT MONO (-589 3800);
FORCEPROP 2 LAST $XR1 145 
J 0
(-469 3800);
DISPLAY 0.638298 (-469 3800);
PAINT MONO (-469 3800);
FORCEPROP 1 LAST COMMENT_BODY TRUE
J 0
(-800 3700);
DISPLAY 1.404255 (-800 3700);
PAINT PEACH (-800 3700);
DISPLAY INVISIBLE (-800 3700);
FORCEPROP 2 LAST CDS_LIB mstr_standard
J 0
(-775 3800);
PAINT MONO (-775 3800);
DISPLAY INVISIBLE (-775 3800);
FORCEPROP 2 LAST PATH I141
J 0
(-600 3875);
DISPLAY 1.021277 (-600 3875);
PAINT ORANGE (-600 3875);
DISPLAY INVISIBLE (-600 3875);
FORCEPROP 1 LAST OFFPAGE TRUE
J 0
(-450 3675);
PAINT GREEN (-450 3675);
DISPLAY INVISIBLE (-450 3675);
FORCEADD OFFPAGE..2
(-775 4200);
FORCEPROP 2 LAST $XR0 145 
J 0
(-586 4200);
DISPLAY 0.638298 (-586 4200);
PAINT MONO (-586 4200);
FORCEPROP 2 LAST $XR1 182 
J 0
(-466 4200);
DISPLAY 0.638298 (-466 4200);
PAINT MONO (-466 4200);
FORCEPROP 1 LAST OFFPAGE TRUE
J 0
(-450 4075);
PAINT GREEN (-450 4075);
DISPLAY INVISIBLE (-450 4075);
FORCEPROP 1 LAST COMMENT_BODY TRUE
J 0
(-820 4105);
DISPLAY 1.404255 (-820 4105);
PAINT PEACH (-820 4105);
DISPLAY INVISIBLE (-820 4105);
FORCEPROP 2 LAST CDS_LIB mstr_standard
J 0
(-775 4200);
PAINT MONO (-775 4200);
DISPLAY INVISIBLE (-775 4200);
FORCEPROP 2 LAST PATH I142
J 0
(-600 4275);
DISPLAY 1.021277 (-600 4275);
PAINT ORANGE (-600 4275);
DISPLAY INVISIBLE (-600 4275);
FORCEADD OFFPAGE..4
(-775 4300);
FORCEPROP 2 LAST $XR0 119 
J 0
(-589 4300);
DISPLAY 0.638298 (-589 4300);
PAINT MONO (-589 4300);
FORCEPROP 2 LAST $XR1 133 
J 0
(-469 4300);
DISPLAY 0.638298 (-469 4300);
PAINT MONO (-469 4300);
FORCEPROP 2 LAST $XR2 146 
J 0
(-349 4300);
DISPLAY 0.638298 (-349 4300);
PAINT MONO (-349 4300);
FORCEPROP 1 LAST COMMENT_BODY TRUE
J 0
(-800 4200);
DISPLAY 1.404255 (-800 4200);
PAINT PEACH (-800 4200);
DISPLAY INVISIBLE (-800 4200);
FORCEPROP 2 LAST CDS_LIB mstr_standard
J 0
(-775 4300);
PAINT MONO (-775 4300);
DISPLAY INVISIBLE (-775 4300);
FORCEPROP 2 LAST PATH I143
J 0
(-600 4375);
DISPLAY 1.021277 (-600 4375);
PAINT ORANGE (-600 4375);
DISPLAY INVISIBLE (-600 4375);
FORCEPROP 1 LAST OFFPAGE TRUE
J 0
(-450 4175);
PAINT GREEN (-450 4175);
DISPLAY INVISIBLE (-450 4175);
FORCEADD OFFPAGE..4
(-775 2100);
FORCEPROP 2 LAST $XR0 133 
J 0
(-589 2100);
DISPLAY 0.638298 (-589 2100);
PAINT MONO (-589 2100);
FORCEPROP 2 LAST $XR1 199 
J 0
(-469 2100);
DISPLAY 0.638298 (-469 2100);
PAINT MONO (-469 2100);
FORCEPROP 2 LAST $XR2 144 
J 0
(-349 2100);
DISPLAY 0.638298 (-349 2100);
PAINT MONO (-349 2100);
FORCEPROP 1 LAST OFFPAGE TRUE
J 0
(-450 1975);
PAINT GREEN (-450 1975);
DISPLAY INVISIBLE (-450 1975);
FORCEPROP 1 LAST COMMENT_BODY TRUE
J 0
(-800 2000);
DISPLAY 1.404255 (-800 2000);
PAINT PEACH (-800 2000);
DISPLAY INVISIBLE (-800 2000);
FORCEPROP 2 LAST CDS_LIB mstr_standard
J 0
(-775 2100);
PAINT MONO (-775 2100);
DISPLAY INVISIBLE (-775 2100);
FORCEPROP 2 LAST PATH I144
J 0
(-600 2175);
DISPLAY 1.021277 (-600 2175);
PAINT ORANGE (-600 2175);
DISPLAY INVISIBLE (-600 2175);
FORCEADD OFFPAGE..4
(-775 2150);
FORCEPROP 2 LAST $XR0 157 
J 0
(-589 2150);
DISPLAY 0.638298 (-589 2150);
PAINT MONO (-589 2150);
FORCEPROP 2 LAST $XR1 186 
J 0
(-469 2150);
DISPLAY 0.638298 (-469 2150);
PAINT MONO (-469 2150);
FORCEPROP 2 LAST $XR2 146 
J 0
(-349 2150);
DISPLAY 0.638298 (-349 2150);
PAINT MONO (-349 2150);
FORCEPROP 1 LAST OFFPAGE TRUE
J 0
(-450 2025);
PAINT GREEN (-450 2025);
DISPLAY INVISIBLE (-450 2025);
FORCEPROP 1 LAST COMMENT_BODY TRUE
J 0
(-800 2050);
DISPLAY 1.404255 (-800 2050);
PAINT PEACH (-800 2050);
DISPLAY INVISIBLE (-800 2050);
FORCEPROP 2 LAST CDS_LIB mstr_standard
J 0
(-775 2150);
PAINT MONO (-775 2150);
DISPLAY INVISIBLE (-775 2150);
FORCEPROP 2 LAST PATH I145
J 0
(-600 2225);
DISPLAY 1.021277 (-600 2225);
PAINT ORANGE (-600 2225);
DISPLAY INVISIBLE (-600 2225);
FORCEADD OFFPAGE..4
(-775 2250);
FORCEPROP 2 LAST $XR0 143 
J 0
(-589 2250);
DISPLAY 0.638298 (-589 2250);
PAINT MONO (-589 2250);
FORCEPROP 2 LAST $XR1 157 
J 0
(-469 2250);
DISPLAY 0.638298 (-469 2250);
PAINT MONO (-469 2250);
FORCEPROP 1 LAST COMMENT_BODY TRUE
J 0
(-800 2150);
DISPLAY 1.404255 (-800 2150);
PAINT PEACH (-800 2150);
DISPLAY INVISIBLE (-800 2150);
FORCEPROP 2 LAST CDS_LIB mstr_standard
J 0
(-775 2250);
PAINT MONO (-775 2250);
DISPLAY INVISIBLE (-775 2250);
FORCEPROP 2 LAST PATH I146
J 0
(-600 2325);
DISPLAY 1.021277 (-600 2325);
PAINT ORANGE (-600 2325);
DISPLAY INVISIBLE (-600 2325);
FORCEPROP 1 LAST OFFPAGE TRUE
J 0
(-450 2125);
PAINT GREEN (-450 2125);
DISPLAY INVISIBLE (-450 2125);
FORCEADD OFFPAGE..4
(-775 2500);
FORCEPROP 2 LAST $XR0 157 
J 0
(-589 2500);
DISPLAY 0.638298 (-589 2500);
PAINT MONO (-589 2500);
FORCEPROP 2 LAST $XR1 147 
J 0
(-469 2500);
DISPLAY 0.638298 (-469 2500);
PAINT MONO (-469 2500);
FORCEPROP 1 LAST COMMENT_BODY TRUE
J 0
(-800 2400);
DISPLAY 1.404255 (-800 2400);
PAINT PEACH (-800 2400);
DISPLAY INVISIBLE (-800 2400);
FORCEPROP 2 LAST CDS_LIB mstr_standard
J 0
(-775 2500);
PAINT MONO (-775 2500);
DISPLAY INVISIBLE (-775 2500);
FORCEPROP 2 LAST PATH I148
J 0
(-600 2575);
DISPLAY 1.021277 (-600 2575);
PAINT ORANGE (-600 2575);
DISPLAY INVISIBLE (-600 2575);
FORCEPROP 1 LAST OFFPAGE TRUE
J 0
(-450 2375);
PAINT GREEN (-450 2375);
DISPLAY INVISIBLE (-450 2375);
FORCEADD OFFPAGE..2
(-775 2400);
FORCEPROP 2 LAST $XR0 145 
J 0
(-586 2400);
DISPLAY 0.638298 (-586 2400);
PAINT MONO (-586 2400);
FORCEPROP 2 LAST $XR1 177 
J 0
(-466 2400);
DISPLAY 0.638298 (-466 2400);
PAINT MONO (-466 2400);
FORCEPROP 1 LAST COMMENT_BODY TRUE
J 0
(-820 2305);
DISPLAY 1.404255 (-820 2305);
PAINT PEACH (-820 2305);
DISPLAY INVISIBLE (-820 2305);
FORCEPROP 2 LAST CDS_LIB mstr_standard
J 0
(-775 2400);
PAINT MONO (-775 2400);
DISPLAY INVISIBLE (-775 2400);
FORCEPROP 2 LAST PATH I150
J 0
(-600 2475);
DISPLAY 1.021277 (-600 2475);
PAINT ORANGE (-600 2475);
DISPLAY INVISIBLE (-600 2475);
FORCEPROP 1 LAST OFFPAGE TRUE
J 0
(-450 2275);
PAINT GREEN (-450 2275);
DISPLAY INVISIBLE (-450 2275);
FORCEADD OFFPAGE..2
(-775 2450);
FORCEPROP 2 LAST $XR3 ?
J 0
(-346 2450);
DISPLAY 0.638298 (-346 2450);
PAINT MONO (-346 2450);
FORCEPROP 2 LAST $XR0 146 
J 0
(-586 2450);
DISPLAY 0.638298 (-586 2450);
PAINT MONO (-586 2450);
FORCEPROP 2 LAST $XR1 120 
J 0
(-466 2450);
DISPLAY 0.638298 (-466 2450);
PAINT MONO (-466 2450);
FORCEPROP 2 LAST $XR2 170 
J 0
(-346 2450);
DISPLAY 0.638298 (-346 2450);
PAINT MONO (-346 2450);
FORCEPROP 1 LAST COMMENT_BODY TRUE
J 0
(-820 2355);
DISPLAY 1.404255 (-820 2355);
PAINT PEACH (-820 2355);
DISPLAY INVISIBLE (-820 2355);
FORCEPROP 2 LAST CDS_LIB mstr_standard
J 0
(-775 2450);
PAINT MONO (-775 2450);
DISPLAY INVISIBLE (-775 2450);
FORCEPROP 2 LAST PATH I151
J 0
(-600 2525);
DISPLAY 1.021277 (-600 2525);
PAINT ORANGE (-600 2525);
DISPLAY INVISIBLE (-600 2525);
FORCEPROP 1 LAST OFFPAGE TRUE
J 0
(-450 2325);
PAINT GREEN (-450 2325);
DISPLAY INVISIBLE (-450 2325);
FORCEADD OFFPAGE..4
(-775 2900);
FORCEPROP 2 LAST $XR0 133 
J 0
(-589 2900);
DISPLAY 0.638298 (-589 2900);
PAINT MONO (-589 2900);
FORCEPROP 2 LAST $XR1 182 
J 0
(-469 2900);
DISPLAY 0.638298 (-469 2900);
PAINT MONO (-469 2900);
FORCEPROP 2 LAST $XR2 147 
J 0
(-349 2900);
DISPLAY 0.638298 (-349 2900);
PAINT MONO (-349 2900);
FORCEPROP 1 LAST COMMENT_BODY TRUE
J 0
(-800 2800);
DISPLAY 1.404255 (-800 2800);
PAINT PEACH (-800 2800);
DISPLAY INVISIBLE (-800 2800);
FORCEPROP 2 LAST CDS_LIB mstr_standard
J 0
(-775 2900);
PAINT MONO (-775 2900);
DISPLAY INVISIBLE (-775 2900);
FORCEPROP 2 LAST PATH I154
J 0
(-600 2975);
DISPLAY 1.021277 (-600 2975);
PAINT ORANGE (-600 2975);
DISPLAY INVISIBLE (-600 2975);
FORCEPROP 1 LAST OFFPAGE TRUE
J 0
(-450 2775);
PAINT GREEN (-450 2775);
DISPLAY INVISIBLE (-450 2775);
FORCEADD OFFPAGE..4
(-775 2850);
FORCEPROP 2 LAST $XR0 133 
J 0
(-589 2850);
DISPLAY 0.638298 (-589 2850);
PAINT MONO (-589 2850);
FORCEPROP 2 LAST $XR1 182 
J 0
(-469 2850);
DISPLAY 0.638298 (-469 2850);
PAINT MONO (-469 2850);
FORCEPROP 2 LAST $XR2 147 
J 0
(-349 2850);
DISPLAY 0.638298 (-349 2850);
PAINT MONO (-349 2850);
FORCEPROP 1 LAST COMMENT_BODY TRUE
J 0
(-800 2750);
DISPLAY 1.404255 (-800 2750);
PAINT PEACH (-800 2750);
DISPLAY INVISIBLE (-800 2750);
FORCEPROP 2 LAST CDS_LIB mstr_standard
J 0
(-775 2850);
PAINT MONO (-775 2850);
DISPLAY INVISIBLE (-775 2850);
FORCEPROP 2 LAST PATH I155
J 0
(-600 2925);
DISPLAY 1.021277 (-600 2925);
PAINT ORANGE (-600 2925);
DISPLAY INVISIBLE (-600 2925);
FORCEPROP 1 LAST OFFPAGE TRUE
J 0
(-450 2725);
PAINT GREEN (-450 2725);
DISPLAY INVISIBLE (-450 2725);
FORCEADD OFFPAGE..2
(-775 2750);
FORCEPROP 2 LAST $XR0 178 
J 0
(-586 2750);
DISPLAY 0.638298 (-586 2750);
PAINT MONO (-586 2750);
FORCEPROP 1 LAST COMMENT_BODY TRUE
J 0
(-820 2655);
DISPLAY 0.872340 (-820 2655);
PAINT GREEN (-820 2655);
DISPLAY INVISIBLE (-820 2655);
FORCEPROP 2 LAST CDS_LIB mstr_standard
J 0
(-775 2750);
PAINT MONO (-775 2750);
DISPLAY INVISIBLE (-775 2750);
FORCEPROP 2 LAST PATH I156
J 0
(-600 2825);
DISPLAY 1.021277 (-600 2825);
PAINT ORANGE (-600 2825);
DISPLAY INVISIBLE (-600 2825);
FORCEPROP 1 LAST OFFPAGE TRUE
J 0
(-450 2625);
DISPLAY 0.872340 (-450 2625);
PAINT GREEN (-450 2625);
DISPLAY INVISIBLE (-450 2625);
FORCEADD OFFPAGE..2
(-775 3000);
FORCEPROP 2 LAST $XR0 145 
J 0
(-586 3000);
DISPLAY 0.638298 (-586 3000);
PAINT MONO (-586 3000);
FORCEPROP 2 LAST $XR1 149 
J 0
(-466 3000);
DISPLAY 0.638298 (-466 3000);
PAINT MONO (-466 3000);
FORCEPROP 1 LAST COMMENT_BODY TRUE
J 0
(-820 2905);
DISPLAY 1.404255 (-820 2905);
PAINT PEACH (-820 2905);
DISPLAY INVISIBLE (-820 2905);
FORCEPROP 2 LAST CDS_LIB mstr_standard
J 0
(-775 3000);
PAINT MONO (-775 3000);
DISPLAY INVISIBLE (-775 3000);
FORCEPROP 1 LAST OFFPAGE TRUE
J 0
(-450 2875);
PAINT GREEN (-450 2875);
DISPLAY INVISIBLE (-450 2875);
FORCEPROP 2 LAST PATH I158
J 0
(-600 3075);
DISPLAY 1.021277 (-600 3075);
PAINT ORANGE (-600 3075);
DISPLAY INVISIBLE (-600 3075);
FORCEADD OFFPAGE..4
(-775 3150);
FORCEPROP 2 LAST $XR0 146 
J 0
(-589 3150);
DISPLAY 0.638298 (-589 3150);
PAINT MONO (-589 3150);
FORCEPROP 2 LAST $XR1 151 
J 0
(-469 3150);
DISPLAY 0.638298 (-469 3150);
PAINT MONO (-469 3150);
FORCEPROP 2 LAST $XR2 191 
J 0
(-469 3150);
DISPLAY 0.638298 (-469 3150);
PAINT MONO (-469 3150);
FORCEPROP 1 LAST OFFPAGE TRUE
J 0
(-450 3025);
DISPLAY 1.404255 (-450 3025);
PAINT GREEN (-450 3025);
DISPLAY INVISIBLE (-450 3025);
FORCEPROP 1 LAST COMMENT_BODY TRUE
J 0
(-800 3050);
DISPLAY 1.404255 (-800 3050);
PAINT PEACH (-800 3050);
DISPLAY INVISIBLE (-800 3050);
FORCEPROP 2 LAST CDS_LIB mstr_standard
J 0
(-775 3150);
PAINT MONO (-775 3150);
DISPLAY INVISIBLE (-775 3150);
FORCEPROP 2 LAST PATH I159
J 0
(-600 3225);
DISPLAY 1.021277 (-600 3225);
PAINT ORANGE (-600 3225);
DISPLAY INVISIBLE (-600 3225);
FORCEADD OFFPAGE..2
(-775 2350);
FORCEPROP 2 LAST $XR0 144 
J 0
(-586 2350);
DISPLAY 0.638298 (-586 2350);
PAINT MONO (-586 2350);
FORCEPROP 2 LAST $XR1 157 
J 0
(-466 2350);
DISPLAY 0.638298 (-466 2350);
PAINT MONO (-466 2350);
FORCEPROP 2 LAST $XR2 190 
J 0
(-346 2350);
DISPLAY 0.638298 (-346 2350);
PAINT MONO (-346 2350);
FORCEPROP 1 LAST COMMENT_BODY TRUE
J 0
(-820 2255);
DISPLAY 1.404255 (-820 2255);
PAINT PEACH (-820 2255);
DISPLAY INVISIBLE (-820 2255);
FORCEPROP 2 LAST CDS_LIB mstr_standard
J 0
(-775 2350);
PAINT MONO (-775 2350);
DISPLAY INVISIBLE (-775 2350);
FORCEPROP 2 LAST PATH I161
J 0
(-600 2425);
DISPLAY 1.021277 (-600 2425);
PAINT ORANGE (-600 2425);
DISPLAY INVISIBLE (-600 2425);
FORCEPROP 1 LAST OFFPAGE TRUE
J 0
(-450 2225);
PAINT GREEN (-450 2225);
DISPLAY INVISIBLE (-450 2225);
FORCEADD OFFPAGE..4
(-775 2550);
FORCEPROP 2 LAST $XR0 139 
J 0
(-589 2550);
DISPLAY 0.638298 (-589 2550);
PAINT MONO (-589 2550);
FORCEPROP 2 LAST $XR1 146 
J 0
(-469 2550);
DISPLAY 0.638298 (-469 2550);
PAINT MONO (-469 2550);
FORCEPROP 1 LAST COMMENT_BODY TRUE
J 0
(-800 2450);
DISPLAY 1.404255 (-800 2450);
PAINT PEACH (-800 2450);
DISPLAY INVISIBLE (-800 2450);
FORCEPROP 2 LAST CDS_LIB mstr_standard
J 0
(-775 2550);
PAINT MONO (-775 2550);
DISPLAY INVISIBLE (-775 2550);
FORCEPROP 2 LAST PATH I164
J 0
(-600 2625);
DISPLAY 1.021277 (-600 2625);
PAINT ORANGE (-600 2625);
DISPLAY INVISIBLE (-600 2625);
FORCEPROP 1 LAST OFFPAGE TRUE
J 0
(-450 2425);
PAINT GREEN (-450 2425);
DISPLAY INVISIBLE (-450 2425);
FORCEADD OFFPAGE..4
(-775 2800);
FORCEPROP 2 LAST $XR0 108 
J 0
(-589 2800);
DISPLAY 0.638298 (-589 2800);
PAINT MONO (-589 2800);
FORCEPROP 2 LAST $XR1 157 
J 0
(-469 2800);
DISPLAY 0.638298 (-469 2800);
PAINT MONO (-469 2800);
FORCEPROP 2 LAST $XR2 146 
J 0
(-349 2800);
DISPLAY 0.638298 (-349 2800);
PAINT MONO (-349 2800);
FORCEPROP 1 LAST COMMENT_BODY TRUE
J 0
(-800 2700);
DISPLAY 1.404255 (-800 2700);
PAINT PEACH (-800 2700);
DISPLAY INVISIBLE (-800 2700);
FORCEPROP 2 LAST CDS_LIB mstr_standard
J 0
(-775 2800);
PAINT MONO (-775 2800);
DISPLAY INVISIBLE (-775 2800);
FORCEPROP 2 LAST PATH I165
J 0
(-600 2875);
DISPLAY 1.021277 (-600 2875);
PAINT ORANGE (-600 2875);
DISPLAY INVISIBLE (-600 2875);
FORCEPROP 1 LAST OFFPAGE TRUE
J 0
(-450 2675);
PAINT GREEN (-450 2675);
DISPLAY INVISIBLE (-450 2675);
FORCEADD OFFPAGE..5
(-7175 2700);
FORCEPROP 2 LAST $XR0 136 
J 0
(-7460 2700);
DISPLAY 0.638298 (-7460 2700);
PAINT MONO (-7460 2700);
FORCEPROP 2 LAST $XR1 175 
J 0
(-7580 2700);
DISPLAY 0.638298 (-7580 2700);
PAINT MONO (-7580 2700);
FORCEPROP 2 LAST CDS_LIB mstr_standard
J 0
(-7175 2700);
PAINT MONO (-7175 2700);
DISPLAY INVISIBLE (-7175 2700);
FORCEPROP 1 LAST COMMENT_BODY TRUE
J 0
(-7075 2625);
DISPLAY 0.872340 (-7075 2625);
PAINT GREEN (-7075 2625);
DISPLAY INVISIBLE (-7075 2625);
FORCEPROP 2 LAST PATH I166
J 0
(-7125 2775);
DISPLAY 1.021277 (-7125 2775);
PAINT ORANGE (-7125 2775);
DISPLAY INVISIBLE (-7125 2775);
FORCEPROP 1 LAST OFFPAGE TRUE
J 0
(-6850 2575);
DISPLAY 0.872340 (-6850 2575);
PAINT GREEN (-6850 2575);
DISPLAY INVISIBLE (-6850 2575);
FORCEADD OFFPAGE..4
R 2
(-7375 4050);
FORCEPROP 2 LAST $XR0 137 
J 0
(-7657 4050);
DISPLAY 0.638298 (-7657 4050);
PAINT MONO (-7657 4050);
FORCEPROP 1 LAST OFFPAGE TRUE
J 2
(-7700 3925);
DISPLAY 0.872340 (-7700 3925);
PAINT GREEN (-7700 3925);
DISPLAY INVISIBLE (-7700 3925);
FORCEPROP 1 LAST COMMENT_BODY TRUE
J 2
(-7350 3950);
DISPLAY 0.872340 (-7350 3950);
PAINT GREEN (-7350 3950);
DISPLAY INVISIBLE (-7350 3950);
FORCEPROP 2 LAST CDS_LIB mstr_standard
J 0
(-7375 4050);
PAINT MONO (-7375 4050);
DISPLAY INVISIBLE (-7375 4050);
FORCEPROP 2 LAST PATH I170
J 0
(-7325 4125);
DISPLAY 1.021277 (-7325 4125);
PAINT ORANGE (-7325 4125);
DISPLAY INVISIBLE (-7325 4125);
FORCEADD OFFPAGE..2
(-775 4150);
FORCEPROP 2 LAST $XR0 119 
J 0
(-586 4150);
DISPLAY 0.638298 (-586 4150);
PAINT MONO (-586 4150);
FORCEPROP 2 LAST $XR1 145 
J 0
(-466 4150);
DISPLAY 0.638298 (-466 4150);
PAINT MONO (-466 4150);
FORCEPROP 2 LAST $XR2 170 
J 0
(-346 4150);
DISPLAY 0.638298 (-346 4150);
PAINT MONO (-346 4150);
FORCEPROP 1 LAST OFFPAGE TRUE
J 0
(-450 4025);
PAINT GREEN (-450 4025);
DISPLAY INVISIBLE (-450 4025);
FORCEPROP 1 LAST COMMENT_BODY TRUE
J 0
(-820 4055);
DISPLAY 1.404255 (-820 4055);
PAINT PEACH (-820 4055);
DISPLAY INVISIBLE (-820 4055);
FORCEPROP 2 LAST CDS_LIB mstr_standard
J 0
(-775 4150);
PAINT MONO (-775 4150);
DISPLAY INVISIBLE (-775 4150);
FORCEPROP 2 LAST PATH I171
J 0
(-600 4225);
DISPLAY 1.021277 (-600 4225);
PAINT ORANGE (-600 4225);
DISPLAY INVISIBLE (-600 4225);
FORCEADD RES..1
(-1450 2200);
FORCEPROP 1 LAST VALUE 33.2
J 2
(-1550 2200);
DISPLAY 0.617021 (-1550 2200);
PAINT SKYBLUE (-1550 2200);
FORCEPROP 1 LAST TOLERANCE 1%
J 0
(-1600 2150);
DISPLAY 0.617021 (-1600 2150);
PAINT SKYBLUE (-1600 2150);
FORCEPROP 1 LAST WATTAGE 1/16W
J 2
(-1650 2200);
DISPLAY 0.617021 (-1650 2200);
PAINT SKYBLUE (-1650 2200);
FORCEPROP 1 LASTPIN (-1550 2200) $PN 1
J 0
(-1538 2212);
DISPLAY 0.617021 (-1538 2212);
PAINT ORANGE (-1538 2212);
FORCEPROP 1 LAST LOCATION R2M3
J 0
(-1475 2225);
DISPLAY 0.617021 (-1475 2225);
PAINT AQUA (-1475 2225);
FORCEPROP 1 LAST MATERIAL CHIP
J 0
(-1500 2150);
DISPLAY 0.617021 (-1500 2150);
PAINT SKYBLUE (-1500 2150);
FORCEPROP 1 LASTPIN (-1350 2200) $PN 2
J 0
(-1388 2212);
DISPLAY 0.617021 (-1388 2212);
PAINT ORANGE (-1388 2212);
FORCEPROP 1 LAST PACK_TYPE 0402
J 0
(-1375 2150);
DISPLAY 0.617021 (-1375 2150);
PAINT SKYBLUE (-1375 2150);
FORCEPROP 1 LAST PART_NUMBER G21796-074
J 0
(-1275 2150);
DISPLAY 0.617021 (-1275 2150);
PAINT BLUE (-1275 2150);
FORCEPROP 2 LAST CDS_LOCATION R2M3
J 0
(-1475 2225);
DISPLAY 0.617021 (-1475 2225);
PAINT AQUA (-1475 2225);
DISPLAY INVISIBLE (-1475 2225);
FORCEPROP 2 LAST CDS_LIB mstr_discrete
J 0
(-1450 2200);
PAINT MONO (-1450 2200);
DISPLAY INVISIBLE (-1450 2200);
FORCEPROP 2 LAST SEC 1
J 0
(-1500 2400);
DISPLAY 0.680851 (-1500 2400);
PAINT MONO (-1500 2400);
DISPLAY INVISIBLE (-1500 2400);
FORCEPROP 2 LAST SEC_TYPE 0402
J 0
(-1500 2400);
DISPLAY 1.021277 (-1500 2400);
PAINT ORANGE (-1500 2400);
DISPLAY INVISIBLE (-1500 2400);
FORCEPROP 2 LAST ROOM CPLD
J 0
(-1500 2340);
DISPLAY 0.787234 (-1500 2340);
PAINT SKYBLUE (-1500 2340);
DISPLAY INVISIBLE (-1500 2340);
FORCEPROP 1 LAST PATH I172
J 0
(-1500 2350);
DISPLAY 0.978723 (-1500 2350);
PAINT WHITE (-1500 2350);
DISPLAY INVISIBLE (-1500 2350);
FORCEADD RES..1
(-1550 4400);
FORCEPROP 1 LAST TOLERANCE 1%
J 0
(-1825 4475);
DISPLAY 0.617021 (-1825 4475);
PAINT SKYBLUE (-1825 4475);
FORCEPROP 1 LAST WATTAGE 1/16W
J 2
(-1625 4475);
DISPLAY 0.617021 (-1625 4475);
PAINT SKYBLUE (-1625 4475);
FORCEPROP 1 LASTPIN (-1650 4400) $PN 1
J 0
(-1638 4412);
DISPLAY 0.617021 (-1638 4412);
PAINT ORANGE (-1638 4412);
FORCEPROP 1 LAST LOCATION R2N1
J 0
(-1600 4450);
DISPLAY 0.617021 (-1600 4450);
PAINT AQUA (-1600 4450);
FORCEPROP 1 LAST VALUE 33.2
J 2
(-1500 4350);
DISPLAY 0.617021 (-1500 4350);
PAINT SKYBLUE (-1500 4350);
FORCEPROP 1 LASTPIN (-1450 4400) $PN 2
J 0
(-1488 4412);
DISPLAY 0.617021 (-1488 4412);
PAINT ORANGE (-1488 4412);
FORCEPROP 1 LAST PACK_TYPE 0402
J 0
(-1350 4500);
DISPLAY 0.617021 (-1350 4500);
PAINT SKYBLUE (-1350 4500);
FORCEPROP 1 LAST PART_NUMBER G21796-074
J 0
(-1475 4450);
DISPLAY 0.617021 (-1475 4450);
PAINT BLUE (-1475 4450);
FORCEPROP 1 LAST MATERIAL CHIP
J 0
(-1475 4500);
DISPLAY 0.617021 (-1475 4500);
PAINT SKYBLUE (-1475 4500);
FORCEPROP 2 LAST CDS_LIB mstr_discrete
J 0
(-1550 4400);
PAINT MONO (-1550 4400);
DISPLAY INVISIBLE (-1550 4400);
FORCEPROP 2 LAST CDS_LOCATION R2N1
J 0
(-1600 4450);
DISPLAY 0.617021 (-1600 4450);
PAINT AQUA (-1600 4450);
DISPLAY INVISIBLE (-1600 4450);
FORCEPROP 1 LAST PATH I173
J 0
(-1600 4550);
DISPLAY 0.978723 (-1600 4550);
PAINT WHITE (-1600 4550);
DISPLAY INVISIBLE (-1600 4550);
FORCEPROP 2 LAST ROOM CPLD
J 0
(-1600 4540);
DISPLAY 0.787234 (-1600 4540);
PAINT SKYBLUE (-1600 4540);
DISPLAY INVISIBLE (-1600 4540);
FORCEPROP 2 LAST SEC_TYPE 0402
J 0
(-1600 4600);
DISPLAY 1.021277 (-1600 4600);
PAINT ORANGE (-1600 4600);
DISPLAY INVISIBLE (-1600 4600);
FORCEPROP 2 LAST SEC 1
J 0
(-1600 4600);
DISPLAY 0.680851 (-1600 4600);
PAINT MONO (-1600 4600);
DISPLAY INVISIBLE (-1600 4600);
FORCEADD RES..1
(-1475 2950);
FORCEPROP 1 LAST VALUE 33.2
J 2
(-1575 2950);
DISPLAY 0.617021 (-1575 2950);
PAINT SKYBLUE (-1575 2950);
FORCEPROP 1 LAST TOLERANCE 1%
J 0
(-1625 2900);
DISPLAY 0.617021 (-1625 2900);
PAINT SKYBLUE (-1625 2900);
FORCEPROP 1 LAST WATTAGE 1/16W
J 2
(-1675 2950);
DISPLAY 0.617021 (-1675 2950);
PAINT SKYBLUE (-1675 2950);
FORCEPROP 1 LASTPIN (-1575 2950) $PN 1
J 0
(-1563 2962);
DISPLAY 0.617021 (-1563 2962);
PAINT ORANGE (-1563 2962);
FORCEPROP 1 LAST MATERIAL CHIP
J 0
(-1525 2900);
DISPLAY 0.617021 (-1525 2900);
PAINT SKYBLUE (-1525 2900);
FORCEPROP 1 LASTPIN (-1375 2950) $PN 2
J 0
(-1413 2962);
DISPLAY 0.617021 (-1413 2962);
PAINT ORANGE (-1413 2962);
FORCEPROP 1 LAST LOCATION R2M7
J 0
(-1500 2975);
DISPLAY 0.617021 (-1500 2975);
PAINT AQUA (-1500 2975);
FORCEPROP 1 LAST PACK_TYPE 0402
J 0
(-1400 2900);
DISPLAY 0.617021 (-1400 2900);
PAINT SKYBLUE (-1400 2900);
FORCEPROP 1 LAST PART_NUMBER G21796-074
J 0
(-1300 2900);
DISPLAY 0.617021 (-1300 2900);
PAINT BLUE (-1300 2900);
FORCEPROP 2 LAST CDS_LOCATION R2M7
J 0
(-1500 2975);
DISPLAY 0.617021 (-1500 2975);
PAINT AQUA (-1500 2975);
DISPLAY INVISIBLE (-1500 2975);
FORCEPROP 2 LAST CDS_LIB mstr_discrete
J 0
(-1475 2950);
PAINT MONO (-1475 2950);
DISPLAY INVISIBLE (-1475 2950);
FORCEPROP 2 LAST SEC_TYPE 0402
J 0
(-1525 3150);
DISPLAY 1.021277 (-1525 3150);
PAINT ORANGE (-1525 3150);
DISPLAY INVISIBLE (-1525 3150);
FORCEPROP 2 LAST SEC 1
J 0
(-1525 3150);
DISPLAY 0.680851 (-1525 3150);
PAINT MONO (-1525 3150);
DISPLAY INVISIBLE (-1525 3150);
FORCEPROP 1 LAST PATH I174
J 0
(-1525 3100);
DISPLAY 0.978723 (-1525 3100);
PAINT WHITE (-1525 3100);
DISPLAY INVISIBLE (-1525 3100);
FORCEPROP 2 LAST ROOM CPLD
J 0
(-1525 3090);
DISPLAY 0.787234 (-1525 3090);
PAINT SKYBLUE (-1525 3090);
DISPLAY INVISIBLE (-1525 3090);
FORCEADD FET_N_DUAL..5
(-2525 775);
FORCEPROP 1 LASTPIN (-2725 675) $PN 2
J 2
(-2722 690);
DISPLAY 0.617021 (-2722 690);
PAINT WHITE (-2722 690);
FORCEPROP 1 LASTPIN (-2525 575) $PN 1
J 2
(-2467 575);
DISPLAY 0.617021 (-2467 575);
PAINT WHITE (-2467 575);
FORCEPROP 1 LASTPIN (-2525 975) $PN 6
J 2
(-2472 940);
DISPLAY 0.617021 (-2472 940);
PAINT WHITE (-2472 940);
FORCEPROP 1 LAST LOCATION Q9A2
J 0
(-2325 775);
DISPLAY 0.617021 (-2325 775);
PAINT AQUA (-2325 775);
FORCEPROP 1 LAST VALUE NTJD4001N
J 0
(-2325 725);
DISPLAY 0.617021 (-2325 725);
PAINT SKYBLUE (-2325 725);
FORCEPROP 1 LAST MATERIAL FET
J 0
(-2325 675);
DISPLAY 0.617021 (-2325 675);
PAINT SKYBLUE (-2325 675);
FORCEPROP 1 LAST PART_NUMBER E40049-001
J 0
(-2325 575);
DISPLAY 0.617021 (-2325 575);
PAINT BLUE (-2325 575);
FORCEPROP 1 LAST PACK_TYPE SMLF
J 0
(-2325 625);
DISPLAY 0.978723 (-2325 625);
PAINT SKYBLUE (-2325 625);
DISPLAY INVISIBLE (-2325 625);
FORCEPROP 2 LAST CDS_LIB mstr_discrete
J 0
(-2525 775);
PAINT MONO (-2525 775);
DISPLAY INVISIBLE (-2525 775);
FORCEPROP 2 LAST SEC 1
J 0
(-2325 875);
DISPLAY 0.680851 (-2325 875);
PAINT MONO (-2325 875);
DISPLAY INVISIBLE (-2325 875);
FORCEPROP 0 LAST BOM_COST SB
J 0
(-2325 975);
DISPLAY 1.021277 (-2325 975);
PAINT ORANGE (-2325 975);
DISPLAY INVISIBLE (-2325 975);
FORCEPROP 2 LAST SEC_TYPE SMLF
J 0
(-2325 875);
DISPLAY 1.021277 (-2325 875);
PAINT ORANGE (-2325 875);
DISPLAY INVISIBLE (-2325 875);
FORCEPROP 0 LAST ROOM SB
J 0
(-2325 875);
DISPLAY 1.021277 (-2325 875);
PAINT ORANGE (-2325 875);
DISPLAY INVISIBLE (-2325 875);
FORCEPROP 1 LAST PATH I175
J 0
(-2325 825);
DISPLAY 0.978723 (-2325 825);
PAINT BLUE (-2325 825);
DISPLAY INVISIBLE (-2325 825);
FORCEPROP 2 LAST CDS_LOCATION Q9A2
J 0
(-2325 775);
DISPLAY 0.617021 (-2325 775);
PAINT AQUA (-2325 775);
DISPLAY INVISIBLE (-2325 775);
FORCEADD OFFPAGE..1
(-3400 675);
FORCEPROP 2 LAST $XR0 119 
J 0
(-3652 675);
DISPLAY 0.638298 (-3652 675);
PAINT MONO (-3652 675);
FORCEPROP 2 LAST CDS_LIB mstr_standard
J 0
(-3400 675);
PAINT MONO (-3400 675);
DISPLAY INVISIBLE (-3400 675);
FORCEPROP 2 LAST PATH I176
J 0
(-3350 750);
DISPLAY 1.021277 (-3350 750);
PAINT ORANGE (-3350 750);
DISPLAY INVISIBLE (-3350 750);
FORCEPROP 1 LAST OFFPAGE TRUE
J 0
(-3075 550);
DISPLAY 0.872340 (-3075 550);
PAINT GREEN (-3075 550);
DISPLAY INVISIBLE (-3075 550);
FORCEPROP 1 LAST COMMENT_BODY TRUE
J 0
(-3275 575);
DISPLAY 0.872340 (-3275 575);
PAINT GREEN (-3275 575);
DISPLAY INVISIBLE (-3275 575);
FORCEADD P3V3_STBY..1
(-500 1750);
FORCEPROP 3 LASTPIN (-500 1700) SIG_NAME P3V3_STBY\g
J 0
(-490 1710);
DISPLAY 0.659574 (-490 1710);
PAINT MONO (-490 1710);
DISPLAY INVISIBLE (-490 1710);
FORCEPROP 1 LAST HDL_POWER P3V3_STBY
J 0
(-800 1625);
DISPLAY 0.872340 (-800 1625);
PAINT ORANGE (-800 1625);
DISPLAY INVISIBLE (-800 1625);
FORCEPROP 1 LAST VOLTAGE 3.3V
J 0
(-545 1707);
DISPLAY 0.340426 (-545 1707);
PAINT SKYBLUE (-545 1707);
DISPLAY INVISIBLE (-545 1707);
FORCEPROP 1 LAST BODY_TYPE PLUMBING
J 0
(-545 1707);
DISPLAY 0.340426 (-545 1707);
PAINT GREEN (-545 1707);
DISPLAY INVISIBLE (-545 1707);
FORCEPROP 2 LAST CDS_LIB mstr_symbols
J 0
(-500 1750);
PAINT MONO (-500 1750);
DISPLAY INVISIBLE (-500 1750);
FORCEPROP 1 LAST SIZE 1B
J 0
(-455 1772);
DISPLAY 0.340426 (-455 1772);
PAINT GREEN (-455 1772);
DISPLAY INVISIBLE (-455 1772);
FORCEPROP 1 LAST PATH I177
J 0
(-455 1752);
DISPLAY 0.340426 (-455 1752);
PAINT GREEN (-455 1752);
DISPLAY INVISIBLE (-455 1752);
FORCEADD RES..1
(-700 1575);
FORCEPROP 1 LAST VALUE 221
J 2
(-725 1475);
DISPLAY 0.617021 (-725 1475);
PAINT SKYBLUE (-725 1475);
FORCEPROP 1 LAST TOLERANCE 1.0%
J 0
(-700 1475);
DISPLAY 0.617021 (-700 1475);
PAINT SKYBLUE (-700 1475);
FORCEPROP 1 LAST MATERIAL CHIP
J 0
(-700 1425);
DISPLAY 0.617021 (-700 1425);
PAINT SKYBLUE (-700 1425);
FORCEPROP 1 LAST WATTAGE 1/16W
J 2
(-725 1425);
DISPLAY 0.617021 (-725 1425);
PAINT SKYBLUE (-725 1425);
FORCEPROP 1 LASTPIN (-800 1575) $PN 1
J 0
(-788 1587);
DISPLAY 0.617021 (-788 1587);
PAINT ORANGE (-788 1587);
FORCEPROP 1 LAST LOCATION R9A20
J 0
(-750 1625);
DISPLAY 0.617021 (-750 1625);
PAINT AQUA (-750 1625);
FORCEPROP 1 LASTPIN (-600 1575) $PN 2
J 0
(-638 1587);
DISPLAY 0.617021 (-638 1587);
PAINT ORANGE (-638 1587);
FORCEPROP 1 LAST PART_NUMBER G21796-271
J 0
(-575 1475);
DISPLAY 0.617021 (-575 1475);
PAINT BLUE (-575 1475);
FORCEPROP 1 LAST PACK_TYPE 0402
J 0
(-575 1425);
DISPLAY 0.617021 (-575 1425);
PAINT SKYBLUE (-575 1425);
FORCEPROP 2 LAST ROOM SB
J 0
(-750 1725);
DISPLAY 1.021277 (-750 1725);
PAINT ORANGE (-750 1725);
DISPLAY INVISIBLE (-750 1725);
FORCEPROP 1 LAST PATH I178
J 0
(-750 1725);
DISPLAY 0.978723 (-750 1725);
PAINT WHITE (-750 1725);
DISPLAY INVISIBLE (-750 1725);
FORCEPROP 2 LAST CDS_LOCATION R9A20
J 0
(-750 1625);
DISPLAY 0.617021 (-750 1625);
PAINT AQUA (-750 1625);
DISPLAY INVISIBLE (-750 1625);
FORCEPROP 2 LAST CDS_LIB mstr_discrete
J 0
(-700 1575);
PAINT MONO (-700 1575);
DISPLAY INVISIBLE (-700 1575);
FORCEPROP 2 LAST SEC_TYPE 0402
J 0
(-750 1775);
DISPLAY 1.021277 (-750 1775);
PAINT ORANGE (-750 1775);
DISPLAY INVISIBLE (-750 1775);
FORCEPROP 2 LAST BOM_COST SB
J 0
(-750 1775);
DISPLAY 1.021277 (-750 1775);
PAINT ORANGE (-750 1775);
DISPLAY INVISIBLE (-750 1775);
FORCEPROP 2 LAST SEC 1
J 0
(-750 1775);
DISPLAY 0.680851 (-750 1775);
PAINT MONO (-750 1775);
DISPLAY INVISIBLE (-750 1775);
FORCEADD LED..3
(-1350 1575);
FORCEPROP 1 LAST PART_NUMBER C97278-010
J 0
(-1350 1450);
DISPLAY 0.617021 (-1350 1450);
PAINT BLUE (-1350 1450);
FORCEPROP 1 LAST COLOR GREEN
J 0
(-1450 1675);
DISPLAY 0.617021 (-1450 1675);
PAINT BLUE (-1450 1675);
FORCEPROP 1 LAST MATERIAL IC
J 0
(-1450 1725);
DISPLAY 0.617021 (-1450 1725);
PAINT SKYBLUE (-1450 1725);
FORCEPROP 2 LASTPIN (-1450 1575) $PN 2
J 2
(-1460 1585);
DISPLAY 0.617021 (-1460 1585);
PAINT ORANGE (-1460 1585);
FORCEPROP 1 LAST LOCATION DS9A5
J 0
(-1450 1775);
DISPLAY 0.617021 (-1450 1775);
PAINT AQUA (-1450 1775);
FORCEPROP 2 LASTPIN (-1250 1575) $PN 1
J 0
(-1240 1585);
DISPLAY 0.617021 (-1240 1585);
PAINT ORANGE (-1240 1585);
FORCEPROP 2 LAST CDS_LIB mstr_discrete
J 0
(-1350 1575);
PAINT MONO (-1350 1575);
DISPLAY INVISIBLE (-1350 1575);
FORCEPROP 2 LAST CDS_LOCATION DS9A5
J 0
(-1450 1775);
DISPLAY 0.617021 (-1450 1775);
PAINT AQUA (-1450 1775);
DISPLAY INVISIBLE (-1450 1775);
FORCEPROP 2 LAST BOM_COST SB
J 0
(-1450 1875);
DISPLAY 1.021277 (-1450 1875);
PAINT ORANGE (-1450 1875);
DISPLAY INVISIBLE (-1450 1875);
FORCEPROP 2 LAST SEC_TYPE A1LF
J 0
(-1450 1825);
DISPLAY 1.021277 (-1450 1825);
PAINT ORANGE (-1450 1825);
DISPLAY INVISIBLE (-1450 1825);
FORCEPROP 1 LAST PACK_TYPE A1LF
J 0
(-1450 1825);
DISPLAY 0.978723 (-1450 1825);
PAINT SKYBLUE (-1450 1825);
DISPLAY INVISIBLE (-1450 1825);
FORCEPROP 2 LAST ROOM SB
J 0
(-1450 1825);
DISPLAY 1.021277 (-1450 1825);
PAINT ORANGE (-1450 1825);
DISPLAY INVISIBLE (-1450 1825);
FORCEPROP 2 LAST SEC 1
J 0
(-1450 1825);
DISPLAY 0.680851 (-1450 1825);
PAINT MONO (-1450 1825);
DISPLAY INVISIBLE (-1450 1825);
FORCEPROP 1 LAST PATH I179
J 0
(-1000 1725);
DISPLAY 0.978723 (-1000 1725);
PAINT BLUE (-1000 1725);
DISPLAY INVISIBLE (-1000 1725);
FORCEADD FET_N_DUAL..5
(-1750 1250);
FORCEPROP 1 LASTPIN (-1950 1150) $PN 5
J 2
(-1947 1165);
DISPLAY 0.617021 (-1947 1165);
PAINT WHITE (-1947 1165);
FORCEPROP 1 LASTPIN (-1750 1050) $PN 4
J 2
(-1692 1050);
DISPLAY 0.617021 (-1692 1050);
PAINT WHITE (-1692 1050);
FORCEPROP 1 LASTPIN (-1750 1450) $PN 3
J 2
(-1697 1415);
DISPLAY 0.617021 (-1697 1415);
PAINT WHITE (-1697 1415);
FORCEPROP 1 LAST LOCATION Q9A2
J 0
(-1550 1250);
DISPLAY 0.617021 (-1550 1250);
PAINT AQUA (-1550 1250);
FORCEPROP 1 LAST PART_NUMBER E40049-001
J 0
(-1550 1050);
DISPLAY 0.617021 (-1550 1050);
PAINT BLUE (-1550 1050);
FORCEPROP 1 LAST VALUE NTJD4001N
J 0
(-1550 1200);
DISPLAY 0.617021 (-1550 1200);
PAINT SKYBLUE (-1550 1200);
FORCEPROP 1 LAST MATERIAL FET
J 0
(-1550 1150);
DISPLAY 0.617021 (-1550 1150);
PAINT SKYBLUE (-1550 1150);
FORCEPROP 1 LAST PACK_TYPE SMLF
J 0
(-1550 1100);
DISPLAY 0.978723 (-1550 1100);
PAINT SKYBLUE (-1550 1100);
DISPLAY INVISIBLE (-1550 1100);
FORCEPROP 2 LAST CDS_LOCATION Q9A2
J 0
(-1550 1250);
DISPLAY 0.617021 (-1550 1250);
PAINT AQUA (-1550 1250);
DISPLAY INVISIBLE (-1550 1250);
FORCEPROP 2 LAST CDS_LIB mstr_discrete
J 0
(-1750 1250);
PAINT MONO (-1750 1250);
DISPLAY INVISIBLE (-1750 1250);
FORCEPROP 2 LAST ROOM SB
J 0
(-1550 1300);
DISPLAY 1.021277 (-1550 1300);
PAINT ORANGE (-1550 1300);
DISPLAY INVISIBLE (-1550 1300);
FORCEPROP 1 LAST PATH I180
J 0
(-1550 1300);
DISPLAY 0.978723 (-1550 1300);
PAINT BLUE (-1550 1300);
DISPLAY INVISIBLE (-1550 1300);
FORCEPROP 2 LAST SEC 2
J 0
(-1550 1350);
DISPLAY 0.680851 (-1550 1350);
PAINT MONO (-1550 1350);
DISPLAY INVISIBLE (-1550 1350);
FORCEPROP 2 LAST SEC_TYPE SMLF
J 0
(-1550 1350);
DISPLAY 1.021277 (-1550 1350);
PAINT ORANGE (-1550 1350);
DISPLAY INVISIBLE (-1550 1350);
FORCEPROP 2 LAST BOM_COST SB
J 0
(-1550 1350);
DISPLAY 1.021277 (-1550 1350);
PAINT ORANGE (-1550 1350);
DISPLAY INVISIBLE (-1550 1350);
FORCEADD GND..1
(-1750 900);
FORCEPROP 3 LASTPIN (-1750 950) SIG_NAME GND\g
J 0
(-1740 960);
DISPLAY 0.659574 (-1740 960);
PAINT MONO (-1740 960);
DISPLAY INVISIBLE (-1740 960);
FORCEPROP 1 LAST PATH I181
J 0
(-1675 900);
DISPLAY 0.872340 (-1675 900);
PAINT AQUA (-1675 900);
DISPLAY INVISIBLE (-1675 900);
FORCEPROP 1 LAST BODY_TYPE PLUMBING
J 0
(-1795 857);
DISPLAY 0.340426 (-1795 857);
PAINT GREEN (-1795 857);
DISPLAY INVISIBLE (-1795 857);
FORCEPROP 1 LAST SIZE 1B
J 0
(-1675 850);
DISPLAY 0.872340 (-1675 850);
PAINT AQUA (-1675 850);
DISPLAY INVISIBLE (-1675 850);
FORCEPROP 2 LAST CDS_LIB mstr_symbols
J 0
(-1750 900);
PAINT MONO (-1750 900);
DISPLAY INVISIBLE (-1750 900);
FORCEPROP 1 LAST VOLTAGE 0.0V
J 0
(-1795 857);
DISPLAY 0.340426 (-1795 857);
PAINT SKYBLUE (-1795 857);
DISPLAY INVISIBLE (-1795 857);
FORCEPROP 1 LAST HDL_POWER GND
J 0
(-1750 1050);
DISPLAY 0.872340 (-1750 1050);
PAINT GREEN (-1750 1050);
DISPLAY INVISIBLE (-1750 1050);
FORCEADD P3V3_STBY..1
(-2525 1600);
FORCEPROP 3 LASTPIN (-2525 1550) SIG_NAME P3V3_STBY\g
J 0
(-2515 1560);
DISPLAY 0.659574 (-2515 1560);
PAINT MONO (-2515 1560);
DISPLAY INVISIBLE (-2515 1560);
FORCEPROP 1 LAST HDL_POWER P3V3_STBY
J 0
(-2825 1475);
DISPLAY 0.872340 (-2825 1475);
PAINT ORANGE (-2825 1475);
DISPLAY INVISIBLE (-2825 1475);
FORCEPROP 1 LAST VOLTAGE 3.3V
J 0
(-2570 1557);
DISPLAY 0.340426 (-2570 1557);
PAINT SKYBLUE (-2570 1557);
DISPLAY INVISIBLE (-2570 1557);
FORCEPROP 1 LAST BODY_TYPE PLUMBING
J 0
(-2570 1557);
DISPLAY 0.340426 (-2570 1557);
PAINT GREEN (-2570 1557);
DISPLAY INVISIBLE (-2570 1557);
FORCEPROP 2 LAST CDS_LIB mstr_symbols
J 0
(-2525 1600);
PAINT MONO (-2525 1600);
DISPLAY INVISIBLE (-2525 1600);
FORCEPROP 1 LAST SIZE 1B
J 0
(-2480 1622);
DISPLAY 0.340426 (-2480 1622);
PAINT GREEN (-2480 1622);
DISPLAY INVISIBLE (-2480 1622);
FORCEPROP 1 LAST PATH I182
J 0
(-2480 1602);
DISPLAY 0.340426 (-2480 1602);
PAINT GREEN (-2480 1602);
DISPLAY INVISIBLE (-2480 1602);
FORCEADD RES..2
(-2525 1400);
FORCEPROP 1 LAST PACK_TYPE 0402
J 0
(-2485 1225);
DISPLAY 0.617021 (-2485 1225);
PAINT SKYBLUE (-2485 1225);
FORCEPROP 1 LASTPIN (-2525 1300) $PN 2
J 0
(-2520 1310);
DISPLAY 0.617021 (-2520 1310);
PAINT ORANGE (-2520 1310);
FORCEPROP 1 LASTPIN (-2525 1500) $PN 1
J 0
(-2520 1462);
DISPLAY 0.617021 (-2520 1462);
PAINT ORANGE (-2520 1462);
FORCEPROP 1 LAST WATTAGE 1/16W
J 0
(-2485 1375);
DISPLAY 0.617021 (-2485 1375);
PAINT SKYBLUE (-2485 1375);
FORCEPROP 1 LAST MATERIAL CHIP
J 0
(-2485 1325);
DISPLAY 0.617021 (-2485 1325);
PAINT SKYBLUE (-2485 1325);
FORCEPROP 1 LAST VALUE 4.75K
J 0
(-2480 1475);
DISPLAY 0.617021 (-2480 1475);
PAINT SKYBLUE (-2480 1475);
FORCEPROP 1 LAST TOLERANCE 1%
J 0
(-2480 1425);
DISPLAY 0.617021 (-2480 1425);
PAINT SKYBLUE (-2480 1425);
FORCEPROP 1 LAST PART_NUMBER G21796-072
J 0
(-2485 1275);
DISPLAY 0.617021 (-2485 1275);
PAINT BLUE (-2485 1275);
FORCEPROP 1 LAST LOCATION R9A18
J 0
(-2480 1525);
DISPLAY 0.617021 (-2480 1525);
PAINT AQUA (-2480 1525);
FORCEPROP 2 LAST CDS_LIB mstr_discrete
J 0
(-2525 1400);
PAINT MONO (-2525 1400);
DISPLAY INVISIBLE (-2525 1400);
FORCEPROP 2 LAST CDS_LOCATION R9A18
J 0
(-2480 1525);
DISPLAY 0.617021 (-2480 1525);
PAINT AQUA (-2480 1525);
DISPLAY INVISIBLE (-2480 1525);
FORCEPROP 2 LAST SEC_TYPE 0402
J 0
(-2475 1625);
DISPLAY 1.021277 (-2475 1625);
PAINT ORANGE (-2475 1625);
DISPLAY INVISIBLE (-2475 1625);
FORCEPROP 0 LAST BOM_COST SB
J 0
(-2475 1725);
DISPLAY 1.021277 (-2475 1725);
PAINT ORANGE (-2475 1725);
DISPLAY INVISIBLE (-2475 1725);
FORCEPROP 2 LAST SEC 1
J 0
(-2475 1625);
DISPLAY 0.680851 (-2475 1625);
PAINT MONO (-2475 1625);
DISPLAY INVISIBLE (-2475 1625);
FORCEPROP 1 LAST PATH I183
J 0
(-2475 1575);
DISPLAY 0.978723 (-2475 1575);
PAINT WHITE (-2475 1575);
DISPLAY INVISIBLE (-2475 1575);
FORCEPROP 0 LAST ROOM SB
J 0
(-2475 1625);
DISPLAY 1.021277 (-2475 1625);
PAINT ORANGE (-2475 1625);
DISPLAY INVISIBLE (-2475 1625);
FORCEADD GND..1
(-2525 475);
FORCEPROP 3 LASTPIN (-2525 525) SIG_NAME GND\g
J 0
(-2515 535);
DISPLAY 0.659574 (-2515 535);
PAINT MONO (-2515 535);
DISPLAY INVISIBLE (-2515 535);
FORCEPROP 1 LAST VOLTAGE 0.0V
J 0
(-2570 432);
DISPLAY 0.340426 (-2570 432);
PAINT SKYBLUE (-2570 432);
DISPLAY INVISIBLE (-2570 432);
FORCEPROP 1 LAST BODY_TYPE PLUMBING
J 0
(-2570 432);
DISPLAY 0.340426 (-2570 432);
PAINT GREEN (-2570 432);
DISPLAY INVISIBLE (-2570 432);
FORCEPROP 1 LAST SIZE 1B
J 0
(-2450 425);
DISPLAY 0.872340 (-2450 425);
PAINT AQUA (-2450 425);
DISPLAY INVISIBLE (-2450 425);
FORCEPROP 1 LAST PATH I184
J 0
(-2450 475);
DISPLAY 0.872340 (-2450 475);
PAINT AQUA (-2450 475);
DISPLAY INVISIBLE (-2450 475);
FORCEPROP 2 LAST CDS_LIB mstr_symbols
J 0
(-2525 475);
PAINT MONO (-2525 475);
DISPLAY INVISIBLE (-2525 475);
FORCEPROP 1 LAST HDL_POWER GND
J 0
(-2525 625);
DISPLAY 0.872340 (-2525 625);
PAINT GREEN (-2525 625);
DISPLAY INVISIBLE (-2525 625);
FORCEADD P3V3_STBY..1
(-2975 1200);
FORCEPROP 3 LASTPIN (-2975 1150) SIG_NAME P3V3_STBY\g
J 0
(-2965 1160);
DISPLAY 0.659574 (-2965 1160);
PAINT MONO (-2965 1160);
DISPLAY INVISIBLE (-2965 1160);
FORCEPROP 1 LAST HDL_POWER P3V3_STBY
J 0
(-3275 1075);
DISPLAY 0.872340 (-3275 1075);
PAINT ORANGE (-3275 1075);
DISPLAY INVISIBLE (-3275 1075);
FORCEPROP 1 LAST VOLTAGE 3.3V
J 0
(-3020 1157);
DISPLAY 0.340426 (-3020 1157);
PAINT SKYBLUE (-3020 1157);
DISPLAY INVISIBLE (-3020 1157);
FORCEPROP 2 LAST CDS_LIB mstr_symbols
J 0
(-2975 1200);
PAINT MONO (-2975 1200);
DISPLAY INVISIBLE (-2975 1200);
FORCEPROP 1 LAST BODY_TYPE PLUMBING
J 0
(-3020 1157);
DISPLAY 0.340426 (-3020 1157);
PAINT GREEN (-3020 1157);
DISPLAY INVISIBLE (-3020 1157);
FORCEPROP 1 LAST PATH I185
J 0
(-2930 1202);
DISPLAY 0.340426 (-2930 1202);
PAINT GREEN (-2930 1202);
DISPLAY INVISIBLE (-2930 1202);
FORCEPROP 1 LAST SIZE 1B
J 0
(-2930 1222);
DISPLAY 0.340426 (-2930 1222);
PAINT GREEN (-2930 1222);
DISPLAY INVISIBLE (-2930 1222);
FORCEADD RES..2
(-2975 950);
FORCEPROP 1 LASTPIN (-2975 850) $PN 2
J 0
(-2970 860);
DISPLAY 0.617021 (-2970 860);
PAINT ORANGE (-2970 860);
FORCEPROP 1 LAST MATERIAL CHIP
J 0
(-2935 875);
DISPLAY 0.617021 (-2935 875);
PAINT SKYBLUE (-2935 875);
FORCEPROP 1 LAST PACK_TYPE 0402
J 0
(-2935 775);
DISPLAY 0.617021 (-2935 775);
PAINT SKYBLUE (-2935 775);
FORCEPROP 1 LAST TOLERANCE 1%
J 0
(-2930 975);
DISPLAY 0.617021 (-2930 975);
PAINT SKYBLUE (-2930 975);
FORCEPROP 1 LAST PART_NUMBER G21796-072
J 0
(-2935 825);
DISPLAY 0.617021 (-2935 825);
PAINT BLUE (-2935 825);
FORCEPROP 1 LAST WATTAGE 1/16W
J 0
(-2935 925);
DISPLAY 0.617021 (-2935 925);
PAINT SKYBLUE (-2935 925);
FORCEPROP 1 LASTPIN (-2975 1050) $PN 1
J 0
(-2970 1012);
DISPLAY 0.617021 (-2970 1012);
PAINT ORANGE (-2970 1012);
FORCEPROP 1 LAST LOCATION R9A21
J 0
(-2930 1075);
DISPLAY 0.617021 (-2930 1075);
PAINT AQUA (-2930 1075);
FORCEPROP 1 LAST VALUE 4.75K
J 0
(-2930 1025);
DISPLAY 0.617021 (-2930 1025);
PAINT SKYBLUE (-2930 1025);
FORCEPROP 2 LAST CDS_LIB mstr_discrete
J 0
(-2975 950);
PAINT MONO (-2975 950);
DISPLAY INVISIBLE (-2975 950);
FORCEPROP 2 LAST SEC_TYPE 0402
J 0
(-2925 1175);
DISPLAY 1.021277 (-2925 1175);
PAINT ORANGE (-2925 1175);
DISPLAY INVISIBLE (-2925 1175);
FORCEPROP 2 LAST SEC 1
J 0
(-2925 1175);
DISPLAY 0.680851 (-2925 1175);
PAINT MONO (-2925 1175);
DISPLAY INVISIBLE (-2925 1175);
FORCEPROP 2 LAST CDS_LOCATION R9A21
J 0
(-2930 1075);
DISPLAY 0.617021 (-2930 1075);
PAINT AQUA (-2930 1075);
DISPLAY INVISIBLE (-2930 1075);
FORCEPROP 1 LAST PATH I186
J 0
(-2925 1125);
DISPLAY 0.978723 (-2925 1125);
PAINT WHITE (-2925 1125);
DISPLAY INVISIBLE (-2925 1125);
FORCEPROP 0 LAST ROOM SB
J 0
(-2925 1175);
DISPLAY 1.021277 (-2925 1175);
PAINT ORANGE (-2925 1175);
DISPLAY INVISIBLE (-2925 1175);
FORCEPROP 0 LAST BOM_COST SB
J 0
(-2925 1275);
DISPLAY 1.021277 (-2925 1275);
PAINT ORANGE (-2925 1275);
DISPLAY INVISIBLE (-2925 1275);
FORCEADD OFFPAGE..2
(-775 2050);
FORCEPROP 2 LAST $XR0 119 
J 0
(-586 2050);
DISPLAY 0.638298 (-586 2050);
PAINT MONO (-586 2050);
FORCEPROP 1 LAST COMMENT_BODY TRUE
J 0
(-820 1955);
DISPLAY 1.404255 (-820 1955);
PAINT PEACH (-820 1955);
DISPLAY INVISIBLE (-820 1955);
FORCEPROP 1 LAST OFFPAGE TRUE
J 0
(-450 1925);
PAINT GREEN (-450 1925);
DISPLAY INVISIBLE (-450 1925);
FORCEPROP 2 LAST CDS_LIB mstr_standard
J 0
(-775 2050);
PAINT MONO (-775 2050);
DISPLAY INVISIBLE (-775 2050);
FORCEPROP 2 LAST PATH I187
J 0
(-600 2125);
DISPLAY 1.021277 (-600 2125);
PAINT ORANGE (-600 2125);
DISPLAY INVISIBLE (-600 2125);
FORCEADD OFFPAGE..2
(-775 2300);
FORCEPROP 2 LAST $XR0 147 
J 0
(-586 2300);
DISPLAY 0.638298 (-586 2300);
PAINT MONO (-586 2300);
FORCEPROP 2 LAST $XR1 157 
J 0
(-466 2300);
DISPLAY 0.638298 (-466 2300);
PAINT MONO (-466 2300);
FORCEPROP 2 LAST $XR2 190 
J 0
(-346 2300);
DISPLAY 0.638298 (-346 2300);
PAINT MONO (-346 2300);
FORCEPROP 1 LAST COMMENT_BODY TRUE
J 0
(-820 2205);
DISPLAY 1.404255 (-820 2205);
PAINT PEACH (-820 2205);
DISPLAY INVISIBLE (-820 2205);
FORCEPROP 2 LAST CDS_LIB mstr_standard
J 0
(-775 2300);
PAINT MONO (-775 2300);
DISPLAY INVISIBLE (-775 2300);
FORCEPROP 2 LAST PATH I188
J 0
(-600 2375);
DISPLAY 1.021277 (-600 2375);
PAINT ORANGE (-600 2375);
DISPLAY INVISIBLE (-600 2375);
FORCEPROP 1 LAST OFFPAGE TRUE
J 0
(-450 2175);
PAINT GREEN (-450 2175);
DISPLAY INVISIBLE (-450 2175);
FORCEADD RES..1
(-6750 3700);
FORCEPROP 1 LAST VALUE 33.2
J 2
(-6800 3650);
DISPLAY 0.617021 (-6800 3650);
PAINT SKYBLUE (-6800 3650);
FORCEPROP 1 LAST LOCATION R7C26
J 0
(-6825 3750);
DISPLAY 0.617021 (-6825 3750);
PAINT AQUA (-6825 3750);
FORCEPROP 1 LASTPIN (-6650 3700) $PN 2
J 0
(-6688 3712);
DISPLAY 0.617021 (-6688 3712);
PAINT WHITE (-6688 3712);
FORCEPROP 1 LASTPIN (-6850 3700) $PN 1
J 0
(-6838 3712);
DISPLAY 0.617021 (-6838 3712);
PAINT WHITE (-6838 3712);
FORCEPROP 1 LAST WATTAGE 1/16W
J 2
(-6600 3650);
DISPLAY 0.617021 (-6600 3650);
PAINT SKYBLUE (-6600 3650);
FORCEPROP 1 LAST PART_NUMBER G21796-074
J 0
(-6825 3600);
DISPLAY 0.617021 (-6825 3600);
PAINT BLUE (-6825 3600);
FORCEPROP 1 LAST PACK_TYPE 0402
J 0
(-6475 3650);
DISPLAY 0.617021 (-6475 3650);
PAINT SKYBLUE (-6475 3650);
FORCEPROP 1 LAST MATERIAL CHIP
J 0
(-6625 3700);
DISPLAY 0.617021 (-6625 3700);
PAINT SKYBLUE (-6625 3700);
FORCEPROP 1 LAST TOLERANCE 1%
J 0
(-6575 3650);
DISPLAY 0.617021 (-6575 3650);
PAINT SKYBLUE (-6575 3650);
FORCEPROP 2 LAST CDS_LOCATION R7C26
J 0
(-6950 3700);
DISPLAY 0.617021 (-6950 3700);
PAINT AQUA (-6950 3700);
DISPLAY INVISIBLE (-6950 3700);
FORCEPROP 2 LAST CDS_LIB mstr_discrete
J 0
(-6750 3700);
DISPLAY 1.617021 (-6750 3700);
PAINT ORANGE (-6750 3700);
DISPLAY INVISIBLE (-6750 3700);
FORCEPROP 2 LAST BOM_COST SM_CONTROLLER
J 0
(-6800 3825);
DISPLAY 1.617021 (-6800 3825);
PAINT WHITE (-6800 3825);
DISPLAY INVISIBLE (-6800 3825);
FORCEPROP 2 LAST SEC 1
J 0
(-6800 3900);
DISPLAY 1.510638 (-6800 3900);
PAINT MONO (-6800 3900);
DISPLAY INVISIBLE (-6800 3900);
FORCEPROP 2 LAST SEC_TYPE 0402
J 0
(-6800 3900);
DISPLAY 1.659574 (-6800 3900);
PAINT ORANGE (-6800 3900);
DISPLAY INVISIBLE (-6800 3900);
FORCEPROP 1 LAST PATH I189
J 0
(-6800 3850);
DISPLAY 0.978723 (-6800 3850);
PAINT WHITE (-6800 3850);
DISPLAY INVISIBLE (-6800 3850);
FORCEPROP 2 LAST ROOM SYS_CLOCK
J 0
(-6800 3850);
DISPLAY 1.127660 (-6800 3850);
PAINT WHITE (-6800 3850);
DISPLAY INVISIBLE (-6800 3850);
FORCEADD OFFPAGE..5
(-7375 3700);
FORCEPROP 2 LAST $XR0 146 
J 0
(-7660 3700);
DISPLAY 0.638298 (-7660 3700);
PAINT MONO (-7660 3700);
FORCEPROP 2 LAST PATH I190
J 0
(-7650 3750);
DISPLAY 1.021277 (-7650 3750);
PAINT ORANGE (-7650 3750);
DISPLAY INVISIBLE (-7650 3750);
FORCEPROP 2 LAST CDS_LIB mstr_standard
J 0
(-7375 3700);
PAINT ORANGE (-7375 3700);
DISPLAY INVISIBLE (-7375 3700);
FORCEPROP 1 LAST COMMENT_BODY TRUE
J 0
(-7275 3625);
DISPLAY 0.872340 (-7275 3625);
PAINT GREEN (-7275 3625);
DISPLAY INVISIBLE (-7275 3625);
FORCEPROP 1 LAST OFFPAGE TRUE
J 0
(-7050 3575);
DISPLAY 0.872340 (-7050 3575);
PAINT GREEN (-7050 3575);
DISPLAY INVISIBLE (-7050 3575);
FORCEADD OFFPAGE..4
R 2
(-7375 3750);
FORCEPROP 2 LAST $XR0 165 
J 0
(-7627 3750);
DISPLAY 0.638298 (-7627 3750);
PAINT MONO (-7627 3750);
FORCEPROP 1 LAST OFFPAGE TRUE
J 2
(-7700 3625);
DISPLAY 0.872340 (-7700 3625);
PAINT GREEN (-7700 3625);
DISPLAY INVISIBLE (-7700 3625);
FORCEPROP 2 LAST PATH I191
J 0
(-7650 3800);
DISPLAY 1.021277 (-7650 3800);
PAINT ORANGE (-7650 3800);
DISPLAY INVISIBLE (-7650 3800);
FORCEPROP 1 LAST COMMENT_BODY TRUE
J 2
(-7350 3650);
DISPLAY 0.872340 (-7350 3650);
PAINT GREEN (-7350 3650);
DISPLAY INVISIBLE (-7350 3650);
FORCEPROP 2 LAST CDS_LIB mstr_standard
J 0
(-7375 3750);
PAINT MONO (-7375 3750);
DISPLAY INVISIBLE (-7375 3750);
FORCEADD OFFPAGE..4
R 2
(-7175 2450);
FORCEPROP 2 LAST $XR0 175 
J 0
(-7427 2450);
DISPLAY 0.638298 (-7427 2450);
PAINT MONO (-7427 2450);
FORCEPROP 2 LAST $XR1 145 
J 0
(-7547 2450);
DISPLAY 0.638298 (-7547 2450);
PAINT MONO (-7547 2450);
FORCEPROP 2 LAST $XR2 190 
J 0
(-7667 2450);
DISPLAY 0.638298 (-7667 2450);
PAINT MONO (-7667 2450);
FORCEPROP 1 LAST OFFPAGE TRUE
J 2
(-7500 2325);
DISPLAY 0.872340 (-7500 2325);
PAINT GREEN (-7500 2325);
DISPLAY INVISIBLE (-7500 2325);
FORCEPROP 2 LAST CDS_LIB mstr_standard
J 0
(-7175 2450);
PAINT ORANGE (-7175 2450);
DISPLAY INVISIBLE (-7175 2450);
FORCEPROP 1 LAST COMMENT_BODY TRUE
J 2
(-7150 2350);
DISPLAY 0.872340 (-7150 2350);
PAINT GREEN (-7150 2350);
DISPLAY INVISIBLE (-7150 2350);
FORCEPROP 2 LAST PATH I196
J 0
(-7125 2525);
DISPLAY 1.021277 (-7125 2525);
PAINT ORANGE (-7125 2525);
DISPLAY INVISIBLE (-7125 2525);
FORCEADD OFFPAGE..4
R 2
(-7175 2400);
FORCEPROP 2 LAST $XR0 157 
J 0
(-7427 2400);
DISPLAY 0.638298 (-7427 2400);
PAINT MONO (-7427 2400);
FORCEPROP 2 LAST $XR1 145 
J 0
(-7547 2400);
DISPLAY 0.638298 (-7547 2400);
PAINT MONO (-7547 2400);
FORCEPROP 1 LAST OFFPAGE TRUE
J 2
(-7500 2275);
DISPLAY 0.872340 (-7500 2275);
PAINT GREEN (-7500 2275);
DISPLAY INVISIBLE (-7500 2275);
FORCEPROP 2 LAST CDS_LIB mstr_standard
J 0
(-7175 2400);
PAINT ORANGE (-7175 2400);
DISPLAY INVISIBLE (-7175 2400);
FORCEPROP 1 LAST COMMENT_BODY TRUE
J 2
(-7150 2300);
DISPLAY 0.872340 (-7150 2300);
PAINT GREEN (-7150 2300);
DISPLAY INVISIBLE (-7150 2300);
FORCEPROP 2 LAST PATH I197
J 0
(-7125 2475);
DISPLAY 1.021277 (-7125 2475);
PAINT ORANGE (-7125 2475);
DISPLAY INVISIBLE (-7125 2475);
FORCEADD OFFPAGE..1
(-7175 2500);
FORCEPROP 2 LAST $XR0 175 
J 0
(-7457 2500);
DISPLAY 0.638298 (-7457 2500);
PAINT MONO (-7457 2500);
FORCEPROP 2 LAST $XR1 145 
J 0
(-7577 2500);
DISPLAY 0.638298 (-7577 2500);
PAINT MONO (-7577 2500);
FORCEPROP 2 LAST CDS_LIB mstr_standard
J 0
(-7175 2500);
PAINT ORANGE (-7175 2500);
DISPLAY INVISIBLE (-7175 2500);
FORCEPROP 1 LAST COMMENT_BODY TRUE
J 0
(-7050 2400);
DISPLAY 0.872340 (-7050 2400);
PAINT GREEN (-7050 2400);
DISPLAY INVISIBLE (-7050 2400);
FORCEPROP 1 LAST OFFPAGE TRUE
J 0
(-6850 2375);
DISPLAY 0.872340 (-6850 2375);
PAINT GREEN (-6850 2375);
DISPLAY INVISIBLE (-6850 2375);
FORCEPROP 2 LAST PATH I198
J 0
(-7125 2575);
DISPLAY 1.021277 (-7125 2575);
PAINT ORANGE (-7125 2575);
DISPLAY INVISIBLE (-7125 2575);
FORCEADD OFFPAGE..4
R 2
(-7375 3250);
FORCEPROP 2 LAST $XR0 133 
J 0
(-7627 3250);
DISPLAY 0.638298 (-7627 3250);
PAINT MONO (-7627 3250);
FORCEPROP 1 LAST OFFPAGE TRUE
J 2
(-7700 3125);
DISPLAY 0.872340 (-7700 3125);
PAINT GREEN (-7700 3125);
DISPLAY INVISIBLE (-7700 3125);
FORCEPROP 2 LAST PATH I2
J 2
(-7425 3325);
DISPLAY 1.021277 (-7425 3325);
PAINT ORANGE (-7425 3325);
DISPLAY INVISIBLE (-7425 3325);
FORCEPROP 1 LAST COMMENT_BODY TRUE
J 2
(-7350 3150);
DISPLAY 0.872340 (-7350 3150);
PAINT GREEN (-7350 3150);
DISPLAY INVISIBLE (-7350 3150);
FORCEPROP 2 LAST CDS_LIB mstr_standard
J 2
(-7375 3250);
PAINT ORANGE (-7375 3250);
DISPLAY INVISIBLE (-7375 3250);
FORCEADD OFFPAGE..1
(-7175 2800);
FORCEPROP 2 LAST $XR0 120 
J 0
(-7457 2800);
DISPLAY 0.638298 (-7457 2800);
PAINT MONO (-7457 2800);
FORCEPROP 2 LAST $XR1 133 
J 0
(-7577 2800);
DISPLAY 0.638298 (-7577 2800);
PAINT MONO (-7577 2800);
FORCEPROP 2 LAST $XR2 143 
J 0
(-7697 2800);
DISPLAY 0.638298 (-7697 2800);
PAINT MONO (-7697 2800);
FORCEPROP 2 LAST CDS_LIB mstr_standard
J 0
(-7175 2800);
PAINT ORANGE (-7175 2800);
DISPLAY INVISIBLE (-7175 2800);
FORCEPROP 1 LAST COMMENT_BODY TRUE
J 0
(-7050 2700);
DISPLAY 0.872340 (-7050 2700);
PAINT GREEN (-7050 2700);
DISPLAY INVISIBLE (-7050 2700);
FORCEPROP 2 LAST PATH I202
J 0
(-7125 2875);
DISPLAY 1.021277 (-7125 2875);
PAINT ORANGE (-7125 2875);
DISPLAY INVISIBLE (-7125 2875);
FORCEPROP 1 LAST OFFPAGE TRUE
J 0
(-6850 2675);
DISPLAY 0.872340 (-6850 2675);
PAINT GREEN (-6850 2675);
DISPLAY INVISIBLE (-6850 2675);
FORCEPROP 2 LAST $XR3 146 
J 0
(-7697 2800);
DISPLAY 0.638298 (-7697 2800);
PAINT MONO (-7697 2800);
FORCEADD OFFPAGE..4
R 2
(-7175 2750);
FORCEPROP 2 LAST $XR0 183 
J 0
(-7427 2750);
DISPLAY 0.638298 (-7427 2750);
PAINT MONO (-7427 2750);
FORCEPROP 2 LAST $XR1 190 
J 0
(-7547 2750);
DISPLAY 0.638298 (-7547 2750);
PAINT MONO (-7547 2750);
FORCEPROP 1 LAST OFFPAGE TRUE
J 2
(-7500 2625);
DISPLAY 0.872340 (-7500 2625);
PAINT GREEN (-7500 2625);
DISPLAY INVISIBLE (-7500 2625);
FORCEPROP 2 LAST CDS_LIB mstr_standard
J 0
(-7175 2750);
PAINT ORANGE (-7175 2750);
DISPLAY INVISIBLE (-7175 2750);
FORCEPROP 1 LAST COMMENT_BODY TRUE
J 2
(-7150 2650);
DISPLAY 0.872340 (-7150 2650);
PAINT GREEN (-7150 2650);
DISPLAY INVISIBLE (-7150 2650);
FORCEPROP 2 LAST PATH I203
J 0
(-7125 2825);
DISPLAY 1.021277 (-7125 2825);
PAINT ORANGE (-7125 2825);
DISPLAY INVISIBLE (-7125 2825);
FORCEADD OFFPAGE..1
(-7375 4350);
FORCEPROP 2 LAST $XR0 133 
J 0
(-7627 4350);
DISPLAY 0.638298 (-7627 4350);
PAINT MONO (-7627 4350);
FORCEPROP 2 LAST $XR1 249 
J 0
(-7747 4350);
DISPLAY 0.638298 (-7747 4350);
PAINT MONO (-7747 4350);
FORCEPROP 2 LAST $XR2 147 
J 0
(-7747 4350);
DISPLAY 0.638298 (-7747 4350);
PAINT MONO (-7747 4350);
FORCEPROP 2 LAST PATH I205
J 0
(-7625 4400);
DISPLAY 1.021277 (-7625 4400);
PAINT ORANGE (-7625 4400);
DISPLAY INVISIBLE (-7625 4400);
FORCEPROP 1 LAST COMMENT_BODY TRUE
J 0
(-7250 4250);
DISPLAY 0.872340 (-7250 4250);
PAINT GREEN (-7250 4250);
DISPLAY INVISIBLE (-7250 4250);
FORCEPROP 2 LAST CDS_LIB mstr_standard
J 0
(-7375 4350);
PAINT ORANGE (-7375 4350);
DISPLAY INVISIBLE (-7375 4350);
FORCEPROP 1 LAST OFFPAGE TRUE
J 0
(-7050 4225);
DISPLAY 0.872340 (-7050 4225);
PAINT GREEN (-7050 4225);
DISPLAY INVISIBLE (-7050 4225);
FORCEADD OFFPAGE..5
(-7175 2600);
FORCEPROP 2 LAST $XR0 190 
J 0
(-7460 2600);
DISPLAY 0.638298 (-7460 2600);
PAINT MONO (-7460 2600);
FORCEPROP 2 LAST PATH I208
J 0
(-7450 2650);
DISPLAY 1.021277 (-7450 2650);
PAINT ORANGE (-7450 2650);
DISPLAY INVISIBLE (-7450 2650);
FORCEPROP 2 LAST CDS_LIB mstr_standard
J 0
(-7175 2600);
PAINT ORANGE (-7175 2600);
DISPLAY INVISIBLE (-7175 2600);
FORCEPROP 1 LAST OFFPAGE TRUE
J 0
(-6850 2475);
DISPLAY 0.872340 (-6850 2475);
PAINT GREEN (-6850 2475);
DISPLAY INVISIBLE (-6850 2475);
FORCEPROP 1 LAST COMMENT_BODY TRUE
J 0
(-7075 2525);
DISPLAY 0.872340 (-7075 2525);
PAINT GREEN (-7075 2525);
DISPLAY INVISIBLE (-7075 2525);
FORCEADD OFFPAGE..5
(-7375 4100);
FORCEPROP 2 LAST $XR0 144 
J 0
(-7660 4100);
DISPLAY 0.638298 (-7660 4100);
PAINT MONO (-7660 4100);
FORCEPROP 2 LAST $XR1 156 
J 0
(-7780 4100);
DISPLAY 0.638298 (-7780 4100);
PAINT MONO (-7780 4100);
FORCEPROP 1 LAST COMMENT_BODY TRUE
J 0
(-7275 4025);
DISPLAY 0.872340 (-7275 4025);
PAINT GREEN (-7275 4025);
DISPLAY INVISIBLE (-7275 4025);
FORCEPROP 1 LAST OFFPAGE TRUE
J 0
(-7050 3975);
DISPLAY 0.872340 (-7050 3975);
PAINT GREEN (-7050 3975);
DISPLAY INVISIBLE (-7050 3975);
FORCEPROP 2 LAST CDS_LIB mstr_standard
J 0
(-7375 4100);
PAINT ORANGE (-7375 4100);
DISPLAY INVISIBLE (-7375 4100);
FORCEPROP 2 LAST PATH I209
J 0
(-7325 4175);
DISPLAY 1.021277 (-7325 4175);
PAINT ORANGE (-7325 4175);
DISPLAY INVISIBLE (-7325 4175);
FORCEADD OFFPAGE..4
R 2
(-7375 4200);
FORCEPROP 2 LAST $XR0 136 
J 0
(-7627 4200);
DISPLAY 0.638298 (-7627 4200);
PAINT MONO (-7627 4200);
FORCEPROP 1 LAST OFFPAGE TRUE
J 2
(-7700 4075);
DISPLAY 0.872340 (-7700 4075);
PAINT GREEN (-7700 4075);
DISPLAY INVISIBLE (-7700 4075);
FORCEPROP 1 LAST COMMENT_BODY TRUE
J 2
(-7350 4100);
DISPLAY 0.872340 (-7350 4100);
PAINT GREEN (-7350 4100);
DISPLAY INVISIBLE (-7350 4100);
FORCEPROP 2 LAST CDS_LIB mstr_standard
J 0
(-7375 4200);
PAINT ORANGE (-7375 4200);
DISPLAY INVISIBLE (-7375 4200);
FORCEPROP 2 LAST PATH I21
J 0
(-7325 4275);
DISPLAY 1.021277 (-7325 4275);
PAINT ORANGE (-7325 4275);
DISPLAY INVISIBLE (-7325 4275);
FORCEADD OFFPAGE..5
(-7175 2850);
FORCEPROP 2 LAST $XR0 156 
J 0
(-7460 2850);
DISPLAY 0.638298 (-7460 2850);
PAINT MONO (-7460 2850);
FORCEPROP 2 LAST PATH I211
J 0
(-7450 2900);
DISPLAY 1.021277 (-7450 2900);
PAINT ORANGE (-7450 2900);
DISPLAY INVISIBLE (-7450 2900);
FORCEPROP 2 LAST CDS_LIB mstr_standard
J 0
(-7175 2850);
PAINT ORANGE (-7175 2850);
DISPLAY INVISIBLE (-7175 2850);
FORCEPROP 1 LAST COMMENT_BODY TRUE
J 0
(-7075 2775);
DISPLAY 1.404255 (-7075 2775);
PAINT PEACH (-7075 2775);
DISPLAY INVISIBLE (-7075 2775);
FORCEPROP 1 LAST OFFPAGE TRUE
J 0
(-6850 2725);
PAINT GREEN (-6850 2725);
DISPLAY INVISIBLE (-6850 2725);
FORCEADD OFFPAGE..5
(-7175 3100);
FORCEPROP 2 LAST $XR0 125 
J 0
(-7460 3100);
DISPLAY 0.638298 (-7460 3100);
PAINT MONO (-7460 3100);
FORCEPROP 2 LAST $XR1 176 
J 0
(-7580 3100);
DISPLAY 0.638298 (-7580 3100);
PAINT MONO (-7580 3100);
FORCEPROP 2 LAST PATH I212
J 0
(-7450 3150);
DISPLAY 1.021277 (-7450 3150);
PAINT ORANGE (-7450 3150);
DISPLAY INVISIBLE (-7450 3150);
FORCEPROP 2 LAST CDS_LIB mstr_standard
J 0
(-7175 3100);
PAINT ORANGE (-7175 3100);
DISPLAY INVISIBLE (-7175 3100);
FORCEPROP 1 LAST OFFPAGE TRUE
J 0
(-6850 2975);
PAINT GREEN (-6850 2975);
DISPLAY INVISIBLE (-6850 2975);
FORCEPROP 1 LAST COMMENT_BODY TRUE
J 0
(-7075 3025);
DISPLAY 1.404255 (-7075 3025);
PAINT PEACH (-7075 3025);
DISPLAY INVISIBLE (-7075 3025);
FORCEADD RES..2
(-1700 4725);
FORCEPROP 1 LAST PACK_TYPE 0402
J 0
(-1660 4550);
DISPLAY 0.617021 (-1660 4550);
PAINT SKYBLUE (-1660 4550);
FORCEPROP 1 LASTPIN (-1700 4625) $PN 2
J 0
(-1695 4635);
DISPLAY 0.617021 (-1695 4635);
PAINT ORANGE (-1695 4635);
FORCEPROP 1 LASTPIN (-1700 4825) $PN 1
J 0
(-1695 4787);
DISPLAY 0.617021 (-1695 4787);
PAINT ORANGE (-1695 4787);
FORCEPROP 1 LAST MATERIAL CHIP
J 0
(-1660 4650);
DISPLAY 0.617021 (-1660 4650);
PAINT SKYBLUE (-1660 4650);
FORCEPROP 1 LAST TOLERANCE 1%
J 0
(-1655 4750);
DISPLAY 0.617021 (-1655 4750);
PAINT SKYBLUE (-1655 4750);
FORCEPROP 1 LAST LOCATION R2U48
J 0
(-1655 4850);
DISPLAY 0.617021 (-1655 4850);
PAINT AQUA (-1655 4850);
FORCEPROP 1 LAST PART_NUMBER G21796-072
J 0
(-1660 4600);
DISPLAY 0.617021 (-1660 4600);
PAINT BLUE (-1660 4600);
FORCEPROP 1 LAST VALUE 4.75K
J 0
(-1655 4800);
DISPLAY 0.617021 (-1655 4800);
PAINT SKYBLUE (-1655 4800);
FORCEPROP 1 LAST WATTAGE 1/16W
J 0
(-1660 4700);
DISPLAY 0.617021 (-1660 4700);
PAINT SKYBLUE (-1660 4700);
FORCEPROP 2 LAST CDS_LIB mstr_discrete
J 0
(-1700 4725);
PAINT ORANGE (-1700 4725);
DISPLAY INVISIBLE (-1700 4725);
FORCEPROP 2 LAST SEC_TYPE 0402
J 0
(-1650 4950);
DISPLAY 1.021277 (-1650 4950);
PAINT ORANGE (-1650 4950);
DISPLAY INVISIBLE (-1650 4950);
FORCEPROP 2 LAST SEC 1
J 0
(-1650 4950);
DISPLAY 0.680851 (-1650 4950);
PAINT MONO (-1650 4950);
DISPLAY INVISIBLE (-1650 4950);
FORCEPROP 1 LAST PATH I213
J 0
(-1650 4900);
DISPLAY 0.978723 (-1650 4900);
PAINT WHITE (-1650 4900);
DISPLAY INVISIBLE (-1650 4900);
FORCEADD P3V3_STBY..1
(-1700 4900);
FORCEPROP 3 LASTPIN (-1700 4850) SIG_NAME P3V3_STBY\g
J 0
(-1690 4860);
DISPLAY 0.659574 (-1690 4860);
PAINT MONO (-1690 4860);
DISPLAY INVISIBLE (-1690 4860);
FORCEPROP 1 LAST HDL_POWER P3V3_STBY
J 0
(-2000 4775);
DISPLAY 0.872340 (-2000 4775);
PAINT ORANGE (-2000 4775);
DISPLAY INVISIBLE (-2000 4775);
FORCEPROP 1 LAST VOLTAGE 3.3V
J 0
(-1745 4857);
DISPLAY 0.340426 (-1745 4857);
PAINT SKYBLUE (-1745 4857);
DISPLAY INVISIBLE (-1745 4857);
FORCEPROP 1 LAST BODY_TYPE PLUMBING
J 0
(-1745 4857);
DISPLAY 0.340426 (-1745 4857);
PAINT GREEN (-1745 4857);
DISPLAY INVISIBLE (-1745 4857);
FORCEPROP 1 LAST SIZE 1B
J 0
(-1655 4922);
DISPLAY 0.340426 (-1655 4922);
PAINT GREEN (-1655 4922);
DISPLAY INVISIBLE (-1655 4922);
FORCEPROP 2 LAST CDS_LIB mstr_symbols
J 0
(-1700 4900);
PAINT ORANGE (-1700 4900);
DISPLAY INVISIBLE (-1700 4900);
FORCEPROP 1 LAST PATH I214
J 0
(-1655 4902);
DISPLAY 0.340426 (-1655 4902);
PAINT GREEN (-1655 4902);
DISPLAY INVISIBLE (-1655 4902);
FORCEADD RES..1
(-1425 4100);
FORCEPROP 1 LAST WATTAGE 1/16W
J 2
(-1550 4050);
DISPLAY 0.617021 (-1550 4050);
PAINT SKYBLUE (-1550 4050);
FORCEPROP 1 LAST VALUE 0.0
J 2
(-1475 4050);
DISPLAY 0.617021 (-1475 4050);
PAINT SKYBLUE (-1475 4050);
FORCEPROP 1 LAST TOLERANCE 5%
J 0
(-1350 4050);
DISPLAY 0.617021 (-1350 4050);
PAINT SKYBLUE (-1350 4050);
FORCEPROP 1 LAST MATERIAL EMPTY
J 0
(-1250 4050);
DISPLAY 0.617021 (-1250 4050);
PAINT RED (-1250 4050);
FORCEPROP 1 LAST PACK_TYPE 0402
J 0
(-1075 4050);
DISPLAY 0.617021 (-1075 4050);
PAINT SKYBLUE (-1075 4050);
FORCEPROP 1 LAST LOCATION R2U50
J 0
(-1550 4150);
DISPLAY 0.617021 (-1550 4150);
PAINT AQUA (-1550 4150);
FORCEPROP 1 LASTPIN (-1525 4100) $PN 1
J 0
(-1513 4112);
DISPLAY 0.617021 (-1513 4112);
PAINT ORANGE (-1513 4112);
FORCEPROP 1 LASTPIN (-1325 4100) $PN 2
J 0
(-1363 4112);
DISPLAY 0.617021 (-1363 4112);
PAINT ORANGE (-1363 4112);
FORCEPROP 1 LAST PART_NUMBER G21497-005
J 0
(-1350 4150);
DISPLAY 0.617021 (-1350 4150);
PAINT BLUE (-1350 4150);
FORCEPROP 2 LAST CDS_LIB mstr_discrete
J 0
(-1425 4100);
PAINT ORANGE (-1425 4100);
DISPLAY INVISIBLE (-1425 4100);
FORCEPROP 2 LAST SEC_TYPE 0402
J 0
(-1475 4300);
DISPLAY 1.021277 (-1475 4300);
PAINT ORANGE (-1475 4300);
DISPLAY INVISIBLE (-1475 4300);
FORCEPROP 2 LAST SEC 1
J 0
(-1475 4300);
DISPLAY 0.680851 (-1475 4300);
PAINT MONO (-1475 4300);
DISPLAY INVISIBLE (-1475 4300);
FORCEPROP 1 LAST PATH I215
J 0
(-1475 4250);
DISPLAY 0.978723 (-1475 4250);
PAINT WHITE (-1475 4250);
DISPLAY INVISIBLE (-1475 4250);
FORCEADD OFFPAGE..4
(-775 4100);
FORCEPROP 2 LAST $XR0 108 
J 0
(-589 4100);
DISPLAY 0.638298 (-589 4100);
PAINT MONO (-589 4100);
FORCEPROP 1 LAST COMMENT_BODY TRUE
J 0
(-800 4000);
DISPLAY 1.404255 (-800 4000);
PAINT PEACH (-800 4000);
DISPLAY INVISIBLE (-800 4000);
FORCEPROP 1 LAST OFFPAGE TRUE
J 0
(-450 3975);
PAINT GREEN (-450 3975);
DISPLAY INVISIBLE (-450 3975);
FORCEPROP 2 LAST CDS_LIB mstr_standard
J 0
(-775 4100);
PAINT ORANGE (-775 4100);
DISPLAY INVISIBLE (-775 4100);
FORCEPROP 2 LAST PATH I216
J 0
(-600 4175);
DISPLAY 1.021277 (-600 4175);
PAINT ORANGE (-600 4175);
DISPLAY INVISIBLE (-600 4175);
FORCEADD OFFPAGE..2
(-775 3700);
FORCEPROP 2 LAST $XR0 133 
J 0
(-586 3700);
DISPLAY 0.638298 (-586 3700);
PAINT MONO (-586 3700);
FORCEPROP 2 LAST $XR1 190 
J 0
(-466 3700);
DISPLAY 0.638298 (-466 3700);
PAINT MONO (-466 3700);
FORCEPROP 2 LAST PATH I217
J 0
(-1050 3750);
DISPLAY 1.021277 (-1050 3750);
PAINT ORANGE (-1050 3750);
DISPLAY INVISIBLE (-1050 3750);
FORCEPROP 1 LAST COMMENT_BODY TRUE
J 0
(-820 3605);
DISPLAY 0.872340 (-820 3605);
PAINT GREEN (-820 3605);
DISPLAY INVISIBLE (-820 3605);
FORCEPROP 2 LAST CDS_LIB mstr_standard
J 0
(-775 3700);
PAINT ORANGE (-775 3700);
DISPLAY INVISIBLE (-775 3700);
FORCEPROP 1 LAST OFFPAGE TRUE
J 0
(-450 3575);
DISPLAY 0.872340 (-450 3575);
PAINT ORANGE (-450 3575);
DISPLAY INVISIBLE (-450 3575);
FORCEADD OFFPAGE..5
(-7375 4150);
FORCEPROP 2 LAST $XR0 156 
J 0
(-7660 4150);
DISPLAY 0.638298 (-7660 4150);
PAINT MONO (-7660 4150);
FORCEPROP 1 LAST OFFPAGE TRUE
J 0
(-7050 4025);
PAINT GREEN (-7050 4025);
DISPLAY INVISIBLE (-7050 4025);
FORCEPROP 1 LAST COMMENT_BODY TRUE
J 0
(-7275 4075);
DISPLAY 1.404255 (-7275 4075);
PAINT PEACH (-7275 4075);
DISPLAY INVISIBLE (-7275 4075);
FORCEPROP 2 LAST PATH I218
J 0
(-7650 4200);
DISPLAY 1.021277 (-7650 4200);
PAINT ORANGE (-7650 4200);
DISPLAY INVISIBLE (-7650 4200);
FORCEPROP 2 LAST CDS_LIB mstr_standard
J 0
(-7375 4150);
PAINT ORANGE (-7375 4150);
DISPLAY INVISIBLE (-7375 4150);
FORCEADD OFFPAGE..5
(-7175 3000);
FORCEPROP 2 LAST $XR0 133 
J 0
(-7460 3000);
DISPLAY 0.638298 (-7460 3000);
PAINT MONO (-7460 3000);
FORCEPROP 2 LAST $XR1 119 
J 0
(-7580 3000);
DISPLAY 0.638298 (-7580 3000);
PAINT MONO (-7580 3000);
FORCEPROP 2 LAST $XR2 146 
J 0
(-7700 3000);
DISPLAY 0.638298 (-7700 3000);
PAINT MONO (-7700 3000);
FORCEPROP 2 LAST CDS_LIB mstr_standard
J 0
(-7175 3000);
PAINT ORANGE (-7175 3000);
DISPLAY INVISIBLE (-7175 3000);
FORCEPROP 1 LAST COMMENT_BODY TRUE
J 0
(-7075 2925);
DISPLAY 1.404255 (-7075 2925);
PAINT PEACH (-7075 2925);
DISPLAY INVISIBLE (-7075 2925);
FORCEPROP 1 LAST OFFPAGE TRUE
J 0
(-6850 2875);
PAINT GREEN (-6850 2875);
DISPLAY INVISIBLE (-6850 2875);
FORCEPROP 2 LAST PATH I22
J 0
(-7125 3075);
DISPLAY 1.021277 (-7125 3075);
PAINT ORANGE (-7125 3075);
DISPLAY INVISIBLE (-7125 3075);
FORCEADD OFFPAGE..5
(-7175 3150);
FORCEPROP 2 LAST $XR0 126 
J 0
(-7460 3150);
DISPLAY 0.638298 (-7460 3150);
PAINT MONO (-7460 3150);
FORCEPROP 2 LAST $XR1 134 
J 0
(-7580 3150);
DISPLAY 0.638298 (-7580 3150);
PAINT MONO (-7580 3150);
FORCEPROP 2 LAST PATH I23
J 0
(-7425 3200);
DISPLAY 1.021277 (-7425 3200);
PAINT ORANGE (-7425 3200);
DISPLAY INVISIBLE (-7425 3200);
FORCEPROP 2 LAST CDS_LIB mstr_standard
J 0
(-7175 3150);
PAINT ORANGE (-7175 3150);
DISPLAY INVISIBLE (-7175 3150);
FORCEPROP 1 LAST OFFPAGE TRUE
J 0
(-6850 3025);
PAINT GREEN (-6850 3025);
DISPLAY INVISIBLE (-6850 3025);
FORCEPROP 1 LAST COMMENT_BODY TRUE
J 0
(-7075 3075);
DISPLAY 1.404255 (-7075 3075);
PAINT PEACH (-7075 3075);
DISPLAY INVISIBLE (-7075 3075);
FORCEADD OFFPAGE..5
(-7175 2900);
FORCEPROP 2 LAST $XR0 125 
J 0
(-7460 2900);
DISPLAY 0.638298 (-7460 2900);
PAINT MONO (-7460 2900);
FORCEPROP 2 LAST $XR1 147 
J 0
(-7580 2900);
DISPLAY 0.638298 (-7580 2900);
PAINT MONO (-7580 2900);
FORCEPROP 2 LAST $XR2 191 
J 0
(-7700 2900);
DISPLAY 0.638298 (-7700 2900);
PAINT MONO (-7700 2900);
FORCEPROP 2 LAST CDS_LIB mstr_standard
J 0
(-7175 2900);
PAINT ORANGE (-7175 2900);
DISPLAY INVISIBLE (-7175 2900);
FORCEPROP 1 LAST COMMENT_BODY TRUE
J 0
(-7075 2825);
DISPLAY 0.872340 (-7075 2825);
PAINT GREEN (-7075 2825);
DISPLAY INVISIBLE (-7075 2825);
FORCEPROP 2 LAST PATH I26
J 0
(-7125 2975);
DISPLAY 1.021277 (-7125 2975);
PAINT ORANGE (-7125 2975);
DISPLAY INVISIBLE (-7125 2975);
FORCEPROP 1 LAST OFFPAGE TRUE
J 0
(-6850 2775);
DISPLAY 0.872340 (-6850 2775);
PAINT GREEN (-6850 2775);
DISPLAY INVISIBLE (-6850 2775);
FORCEADD OFFPAGE..5
(-7175 2650);
FORCEPROP 2 LAST $XR0 136 
J 0
(-7460 2650);
DISPLAY 0.638298 (-7460 2650);
PAINT MONO (-7460 2650);
FORCEPROP 2 LAST $XR1 139 
J 0
(-7580 2650);
DISPLAY 0.638298 (-7580 2650);
PAINT MONO (-7580 2650);
FORCEPROP 2 LAST $XR2 191 
J 0
(-7700 2650);
DISPLAY 0.638298 (-7700 2650);
PAINT MONO (-7700 2650);
FORCEPROP 2 LAST PATH I29
J 0
(-7425 2700);
DISPLAY 1.021277 (-7425 2700);
PAINT ORANGE (-7425 2700);
DISPLAY INVISIBLE (-7425 2700);
FORCEPROP 2 LAST CDS_LIB mstr_standard
J 0
(-7175 2650);
PAINT ORANGE (-7175 2650);
DISPLAY INVISIBLE (-7175 2650);
FORCEPROP 1 LAST OFFPAGE TRUE
J 0
(-6850 2525);
PAINT GREEN (-6850 2525);
DISPLAY INVISIBLE (-6850 2525);
FORCEPROP 1 LAST COMMENT_BODY TRUE
J 0
(-7075 2575);
DISPLAY 1.404255 (-7075 2575);
PAINT PEACH (-7075 2575);
DISPLAY INVISIBLE (-7075 2575);
FORCEADD OFFPAGE..1
(-7175 2100);
FORCEPROP 2 LAST $XR0 133 
J 0
(-7427 2100);
DISPLAY 0.638298 (-7427 2100);
PAINT MONO (-7427 2100);
FORCEPROP 1 LAST OFFPAGE TRUE
J 0
(-6850 1975);
PAINT GREEN (-6850 1975);
DISPLAY INVISIBLE (-6850 1975);
FORCEPROP 1 LAST COMMENT_BODY TRUE
J 0
(-7050 2000);
DISPLAY 1.404255 (-7050 2000);
PAINT PEACH (-7050 2000);
DISPLAY INVISIBLE (-7050 2000);
FORCEPROP 2 LAST CDS_LIB mstr_standard
J 0
(-7175 2100);
PAINT ORANGE (-7175 2100);
DISPLAY INVISIBLE (-7175 2100);
FORCEPROP 2 LAST PATH I31
J 0
(-7125 2175);
DISPLAY 1.021277 (-7125 2175);
PAINT ORANGE (-7125 2175);
DISPLAY INVISIBLE (-7125 2175);
FORCEADD OFFPAGE..2
(-775 3500);
FORCEPROP 2 LAST $XR0 126 
J 0
(-586 3500);
DISPLAY 0.638298 (-586 3500);
PAINT MONO (-586 3500);
FORCEPROP 2 LAST $XR1 146 
J 0
(-466 3500);
DISPLAY 0.638298 (-466 3500);
PAINT MONO (-466 3500);
FORCEPROP 1 LAST COMMENT_BODY TRUE
J 0
(-820 3405);
DISPLAY 1.404255 (-820 3405);
PAINT PEACH (-820 3405);
DISPLAY INVISIBLE (-820 3405);
FORCEPROP 2 LAST CDS_LIB mstr_standard
J 0
(-775 3500);
PAINT ORANGE (-775 3500);
DISPLAY INVISIBLE (-775 3500);
FORCEPROP 2 LAST PATH I32
J 0
(-575 3550);
DISPLAY 1.021277 (-575 3550);
PAINT ORANGE (-575 3550);
DISPLAY INVISIBLE (-575 3550);
FORCEPROP 1 LAST OFFPAGE TRUE
J 0
(-450 3375);
PAINT GREEN (-450 3375);
DISPLAY INVISIBLE (-450 3375);
FORCEADD OFFPAGE..3
(-775 3450);
FORCEPROP 2 LAST $XR0 138 
J 0
(-561 3450);
DISPLAY 0.638298 (-561 3450);
PAINT MONO (-561 3450);
FORCEPROP 1 LAST COMMENT_BODY TRUE
J 0
(-825 3350);
DISPLAY 1.404255 (-825 3350);
PAINT PEACH (-825 3350);
DISPLAY INVISIBLE (-825 3350);
FORCEPROP 2 LAST CDS_LIB mstr_standard
J 0
(-775 3450);
PAINT ORANGE (-775 3450);
DISPLAY INVISIBLE (-775 3450);
FORCEPROP 2 LAST PATH I33
J 0
(-550 3500);
DISPLAY 1.021277 (-550 3500);
PAINT ORANGE (-550 3500);
DISPLAY INVISIBLE (-550 3500);
FORCEPROP 1 LAST OFFPAGE TRUE
J 0
(-450 3325);
PAINT GREEN (-450 3325);
DISPLAY INVISIBLE (-450 3325);
FORCEADD OFFPAGE..2
(-775 3550);
FORCEPROP 2 LAST $XR0 247 
J 0
(-586 3550);
DISPLAY 0.638298 (-586 3550);
PAINT MONO (-586 3550);
FORCEPROP 2 LAST $XR1 ?
J 0
(-586 3550);
DISPLAY 0.638298 (-586 3550);
PAINT MONO (-586 3550);
FORCEPROP 1 LAST COMMENT_BODY TRUE
J 0
(-820 3455);
DISPLAY 0.872340 (-820 3455);
PAINT GREEN (-820 3455);
DISPLAY INVISIBLE (-820 3455);
FORCEPROP 2 LAST CDS_LIB mstr_standard
J 0
(-775 3550);
PAINT ORANGE (-775 3550);
DISPLAY INVISIBLE (-775 3550);
FORCEPROP 2 LAST PATH I34
J 0
(-550 3600);
DISPLAY 1.021277 (-550 3600);
PAINT ORANGE (-550 3600);
DISPLAY INVISIBLE (-550 3600);
FORCEPROP 1 LAST OFFPAGE TRUE
J 0
(-450 3425);
DISPLAY 0.872340 (-450 3425);
PAINT GREEN (-450 3425);
DISPLAY INVISIBLE (-450 3425);
FORCEADD OFFPAGE..4
(-775 3650);
FORCEPROP 2 LAST $XR0 136 
J 0
(-589 3650);
DISPLAY 0.638298 (-589 3650);
PAINT MONO (-589 3650);
FORCEPROP 1 LAST COMMENT_BODY TRUE
J 0
(-800 3550);
DISPLAY 1.404255 (-800 3550);
PAINT PEACH (-800 3550);
DISPLAY INVISIBLE (-800 3550);
FORCEPROP 2 LAST CDS_LIB mstr_standard
J 0
(-775 3650);
PAINT ORANGE (-775 3650);
DISPLAY INVISIBLE (-775 3650);
FORCEPROP 2 LAST PATH I35
J 0
(-575 3700);
DISPLAY 1.021277 (-575 3700);
PAINT ORANGE (-575 3700);
DISPLAY INVISIBLE (-575 3700);
FORCEPROP 1 LAST OFFPAGE TRUE
J 0
(-450 3525);
PAINT GREEN (-450 3525);
DISPLAY INVISIBLE (-450 3525);
FORCEADD OFFPAGE..3
(-775 3750);
FORCEPROP 2 LAST $XR0 135 
J 0
(-561 3750);
DISPLAY 0.638298 (-561 3750);
PAINT MONO (-561 3750);
FORCEPROP 1 LAST COMMENT_BODY TRUE
J 0
(-825 3650);
DISPLAY 1.404255 (-825 3650);
PAINT PEACH (-825 3650);
DISPLAY INVISIBLE (-825 3650);
FORCEPROP 2 LAST CDS_LIB mstr_standard
J 0
(-775 3750);
PAINT ORANGE (-775 3750);
DISPLAY INVISIBLE (-775 3750);
FORCEPROP 2 LAST PATH I37
J 0
(-550 3800);
DISPLAY 1.021277 (-550 3800);
PAINT ORANGE (-550 3800);
DISPLAY INVISIBLE (-550 3800);
FORCEPROP 1 LAST OFFPAGE TRUE
J 0
(-450 3625);
PAINT GREEN (-450 3625);
DISPLAY INVISIBLE (-450 3625);
FORCEADD OFFPAGE..4
(-775 4400);
FORCEPROP 2 LAST $XR0 190 
J 0
(-589 4400);
DISPLAY 0.638298 (-589 4400);
PAINT MONO (-589 4400);
FORCEPROP 1 LAST COMMENT_BODY TRUE
J 0
(-800 4300);
DISPLAY 1.404255 (-800 4300);
PAINT PEACH (-800 4300);
DISPLAY INVISIBLE (-800 4300);
FORCEPROP 2 LAST CDS_LIB mstr_standard
J 0
(-775 4400);
PAINT ORANGE (-775 4400);
DISPLAY INVISIBLE (-775 4400);
FORCEPROP 2 LAST PATH I39
J 0
(-600 4475);
DISPLAY 1.021277 (-600 4475);
PAINT ORANGE (-600 4475);
DISPLAY INVISIBLE (-600 4475);
FORCEPROP 1 LAST OFFPAGE TRUE
J 0
(-450 4275);
PAINT GREEN (-450 4275);
DISPLAY INVISIBLE (-450 4275);
FORCEADD OFFPAGE..4
(-775 4350);
FORCEPROP 2 LAST $XR0 120 
J 0
(-589 4350);
DISPLAY 0.638298 (-589 4350);
PAINT MONO (-589 4350);
FORCEPROP 2 LAST $XR1 133 
J 0
(-469 4350);
DISPLAY 0.638298 (-469 4350);
PAINT MONO (-469 4350);
FORCEPROP 2 LAST $XR2 144 
J 0
(-349 4350);
DISPLAY 0.638298 (-349 4350);
PAINT MONO (-349 4350);
FORCEPROP 1 LAST COMMENT_BODY TRUE
J 0
(-800 4250);
DISPLAY 1.404255 (-800 4250);
PAINT PEACH (-800 4250);
DISPLAY INVISIBLE (-800 4250);
FORCEPROP 2 LAST CDS_LIB mstr_standard
J 0
(-775 4350);
PAINT ORANGE (-775 4350);
DISPLAY INVISIBLE (-775 4350);
FORCEPROP 2 LAST PATH I40
J 0
(-600 4425);
DISPLAY 1.021277 (-600 4425);
PAINT ORANGE (-600 4425);
DISPLAY INVISIBLE (-600 4425);
FORCEPROP 1 LAST OFFPAGE TRUE
J 0
(-450 4225);
PAINT GREEN (-450 4225);
DISPLAY INVISIBLE (-450 4225);
FORCEADD OFFPAGE..2
(-775 4250);
FORCEPROP 2 LAST $XR0 133 
J 0
(-586 4250);
DISPLAY 0.638298 (-586 4250);
PAINT MONO (-586 4250);
FORCEPROP 2 LAST $XR1 170 
J 0
(-466 4250);
DISPLAY 0.638298 (-466 4250);
PAINT MONO (-466 4250);
FORCEPROP 2 LAST $XR2 95 
J 0
(-346 4250);
DISPLAY 0.638298 (-346 4250);
PAINT MONO (-346 4250);
FORCEPROP 2 LAST $XR3 120 
J 0
(-256 4250);
DISPLAY 0.638298 (-256 4250);
PAINT MONO (-256 4250);
FORCEPROP 2 LAST $XR4 146 
J 0
(-136 4250);
DISPLAY 0.638298 (-136 4250);
PAINT MONO (-136 4250);
FORCEPROP 2 LAST $XR5 ?
J 0
(-136 4250);
DISPLAY 0.638298 (-136 4250);
PAINT MONO (-136 4250);
FORCEPROP 1 LAST COMMENT_BODY TRUE
J 0
(-820 4155);
DISPLAY 1.404255 (-820 4155);
PAINT PEACH (-820 4155);
DISPLAY INVISIBLE (-820 4155);
FORCEPROP 2 LAST CDS_LIB mstr_standard
J 0
(-775 4250);
PAINT ORANGE (-775 4250);
DISPLAY INVISIBLE (-775 4250);
FORCEPROP 1 LAST OFFPAGE TRUE
J 0
(-450 4125);
PAINT GREEN (-450 4125);
DISPLAY INVISIBLE (-450 4125);
FORCEPROP 2 LAST PATH I42
J 0
(-450 4300);
DISPLAY 1.021277 (-450 4300);
PAINT ORANGE (-450 4300);
DISPLAY INVISIBLE (-450 4300);
FORCEADD OFFPAGE..4
(-775 4050);
FORCEPROP 2 LAST $XR0 108 
J 0
(-589 4050);
DISPLAY 0.638298 (-589 4050);
PAINT MONO (-589 4050);
FORCEPROP 2 LAST $XR1 133 
J 0
(-469 4050);
DISPLAY 0.638298 (-469 4050);
PAINT MONO (-469 4050);
FORCEPROP 1 LAST COMMENT_BODY TRUE
J 0
(-800 3950);
DISPLAY 1.404255 (-800 3950);
PAINT PEACH (-800 3950);
DISPLAY INVISIBLE (-800 3950);
FORCEPROP 2 LAST CDS_LIB mstr_standard
J 0
(-775 4050);
PAINT ORANGE (-775 4050);
DISPLAY INVISIBLE (-775 4050);
FORCEPROP 1 LAST OFFPAGE TRUE
J 0
(-450 3925);
PAINT GREEN (-450 3925);
DISPLAY INVISIBLE (-450 3925);
FORCEPROP 2 LAST PATH I46
J 0
(-600 4125);
DISPLAY 1.021277 (-600 4125);
PAINT ORANGE (-600 4125);
DISPLAY INVISIBLE (-600 4125);
FORCEADD OFFPAGE..4
(-775 3950);
FORCEPROP 2 LAST $XR0 120 
J 0
(-589 3950);
DISPLAY 0.638298 (-589 3950);
PAINT MONO (-589 3950);
FORCEPROP 2 LAST $XR1 133 
J 0
(-469 3950);
DISPLAY 0.638298 (-469 3950);
PAINT MONO (-469 3950);
FORCEPROP 2 LAST $XR2 146 
J 0
(-349 3950);
DISPLAY 0.638298 (-349 3950);
PAINT MONO (-349 3950);
FORCEPROP 1 LAST COMMENT_BODY TRUE
J 0
(-800 3850);
DISPLAY 1.404255 (-800 3850);
PAINT PEACH (-800 3850);
DISPLAY INVISIBLE (-800 3850);
FORCEPROP 2 LAST CDS_LIB mstr_standard
J 0
(-775 3950);
PAINT ORANGE (-775 3950);
DISPLAY INVISIBLE (-775 3950);
FORCEPROP 2 LAST PATH I47
J 0
(-575 4000);
DISPLAY 1.021277 (-575 4000);
PAINT ORANGE (-575 4000);
DISPLAY INVISIBLE (-575 4000);
FORCEPROP 1 LAST OFFPAGE TRUE
J 0
(-450 3825);
PAINT GREEN (-450 3825);
DISPLAY INVISIBLE (-450 3825);
FORCEADD OFFPAGE..4
(-775 4000);
FORCEPROP 2 LAST $XR0 108 
J 0
(-589 4000);
DISPLAY 0.638298 (-589 4000);
PAINT MONO (-589 4000);
FORCEPROP 2 LAST $XR1 133 
J 0
(-469 4000);
DISPLAY 0.638298 (-469 4000);
PAINT MONO (-469 4000);
FORCEPROP 1 LAST COMMENT_BODY TRUE
J 0
(-800 3900);
DISPLAY 1.404255 (-800 3900);
PAINT PEACH (-800 3900);
DISPLAY INVISIBLE (-800 3900);
FORCEPROP 2 LAST CDS_LIB mstr_standard
J 0
(-775 4000);
PAINT ORANGE (-775 4000);
DISPLAY INVISIBLE (-775 4000);
FORCEPROP 1 LAST OFFPAGE TRUE
J 0
(-450 3875);
PAINT GREEN (-450 3875);
DISPLAY INVISIBLE (-450 3875);
FORCEPROP 2 LAST PATH I48
J 0
(-600 4075);
DISPLAY 1.021277 (-600 4075);
PAINT ORANGE (-600 4075);
DISPLAY INVISIBLE (-600 4075);
FORCEADD OFFPAGE..4
(-775 3900);
FORCEPROP 2 LAST $XR0 164 
J 0
(-589 3900);
DISPLAY 0.638298 (-589 3900);
PAINT MONO (-589 3900);
FORCEPROP 2 LAST $XR1 145 
J 0
(-469 3900);
DISPLAY 0.638298 (-469 3900);
PAINT MONO (-469 3900);
FORCEPROP 1 LAST COMMENT_BODY TRUE
J 0
(-800 3800);
DISPLAY 1.404255 (-800 3800);
PAINT PEACH (-800 3800);
DISPLAY INVISIBLE (-800 3800);
FORCEPROP 2 LAST CDS_LIB mstr_standard
J 0
(-775 3900);
PAINT ORANGE (-775 3900);
DISPLAY INVISIBLE (-775 3900);
FORCEPROP 2 LAST PATH I49
J 0
(-600 3975);
DISPLAY 1.021277 (-600 3975);
PAINT ORANGE (-600 3975);
DISPLAY INVISIBLE (-600 3975);
FORCEPROP 1 LAST OFFPAGE TRUE
J 0
(-450 3775);
PAINT GREEN (-450 3775);
DISPLAY INVISIBLE (-450 3775);
FORCEADD OFFPAGE..4
(-775 3850);
FORCEPROP 2 LAST $XR0 164 
J 0
(-589 3850);
DISPLAY 0.638298 (-589 3850);
PAINT MONO (-589 3850);
FORCEPROP 2 LAST $XR1 145 
J 0
(-469 3850);
DISPLAY 0.638298 (-469 3850);
PAINT MONO (-469 3850);
FORCEPROP 1 LAST COMMENT_BODY TRUE
J 0
(-800 3750);
DISPLAY 1.404255 (-800 3750);
PAINT PEACH (-800 3750);
DISPLAY INVISIBLE (-800 3750);
FORCEPROP 2 LAST CDS_LIB mstr_standard
J 0
(-775 3850);
PAINT ORANGE (-775 3850);
DISPLAY INVISIBLE (-775 3850);
FORCEPROP 2 LAST PATH I50
J 0
(-600 3925);
DISPLAY 1.021277 (-600 3925);
PAINT ORANGE (-600 3925);
DISPLAY INVISIBLE (-600 3925);
FORCEPROP 1 LAST OFFPAGE TRUE
J 0
(-450 3725);
PAINT GREEN (-450 3725);
DISPLAY INVISIBLE (-450 3725);
FORCEADD OFFPAGE..3
(-775 3600);
FORCEPROP 2 LAST $XR0 247 
J 0
(-561 3600);
DISPLAY 0.638298 (-561 3600);
PAINT MONO (-561 3600);
FORCEPROP 2 LAST $XR1 ?
J 0
(-561 3600);
DISPLAY 0.638298 (-561 3600);
PAINT MONO (-561 3600);
FORCEPROP 1 LAST COMMENT_BODY TRUE
J 0
(-825 3500);
DISPLAY 1.404255 (-825 3500);
PAINT PEACH (-825 3500);
DISPLAY INVISIBLE (-825 3500);
FORCEPROP 2 LAST CDS_LIB mstr_standard
J 0
(-775 3600);
PAINT ORANGE (-775 3600);
DISPLAY INVISIBLE (-775 3600);
FORCEPROP 2 LAST PATH I51
J 0
(-550 3650);
DISPLAY 1.021277 (-550 3650);
PAINT ORANGE (-550 3650);
DISPLAY INVISIBLE (-550 3650);
FORCEPROP 1 LAST OFFPAGE TRUE
J 0
(-450 3475);
PAINT GREEN (-450 3475);
DISPLAY INVISIBLE (-450 3475);
FORCEADD OFFPAGE..2
(-775 3400);
FORCEPROP 2 LAST $XR0 138 
J 0
(-586 3400);
DISPLAY 0.638298 (-586 3400);
PAINT MONO (-586 3400);
FORCEPROP 1 LAST COMMENT_BODY TRUE
J 0
(-820 3305);
DISPLAY 0.872340 (-820 3305);
PAINT GREEN (-820 3305);
DISPLAY INVISIBLE (-820 3305);
FORCEPROP 2 LAST CDS_LIB mstr_standard
J 0
(-775 3400);
PAINT ORANGE (-775 3400);
DISPLAY INVISIBLE (-775 3400);
FORCEPROP 2 LAST PATH I52
J 0
(-550 3450);
DISPLAY 1.021277 (-550 3450);
PAINT ORANGE (-550 3450);
DISPLAY INVISIBLE (-550 3450);
FORCEPROP 1 LAST OFFPAGE TRUE
J 0
(-450 3275);
DISPLAY 0.872340 (-450 3275);
PAINT GREEN (-450 3275);
DISPLAY INVISIBLE (-450 3275);
FORCEADD OFFPAGE..4
(-775 3350);
FORCEPROP 2 LAST $XR0 125 
J 0
(-589 3350);
DISPLAY 0.638298 (-589 3350);
PAINT MONO (-589 3350);
FORCEPROP 1 LAST COMMENT_BODY TRUE
J 0
(-800 3250);
DISPLAY 0.872340 (-800 3250);
PAINT GREEN (-800 3250);
DISPLAY INVISIBLE (-800 3250);
FORCEPROP 2 LAST CDS_LIB mstr_standard
J 0
(-775 3350);
PAINT ORANGE (-775 3350);
DISPLAY INVISIBLE (-775 3350);
FORCEPROP 2 LAST PATH I53
J 0
(-575 3425);
DISPLAY 1.021277 (-575 3425);
PAINT ORANGE (-575 3425);
DISPLAY INVISIBLE (-575 3425);
FORCEPROP 1 LAST OFFPAGE TRUE
J 0
(-450 3225);
DISPLAY 0.872340 (-450 3225);
PAINT GREEN (-450 3225);
DISPLAY INVISIBLE (-450 3225);
FORCEADD OFFPAGE..3
(-775 3300);
FORCEPROP 2 LAST $XR0 138 
J 0
(-561 3300);
DISPLAY 0.638298 (-561 3300);
PAINT MONO (-561 3300);
FORCEPROP 1 LAST COMMENT_BODY TRUE
J 0
(-825 3200);
DISPLAY 0.872340 (-825 3200);
PAINT GREEN (-825 3200);
DISPLAY INVISIBLE (-825 3200);
FORCEPROP 2 LAST CDS_LIB mstr_standard
J 0
(-775 3300);
PAINT ORANGE (-775 3300);
DISPLAY INVISIBLE (-775 3300);
FORCEPROP 2 LAST PATH I54
J 0
(-550 3350);
DISPLAY 1.021277 (-550 3350);
PAINT ORANGE (-550 3350);
DISPLAY INVISIBLE (-550 3350);
FORCEPROP 1 LAST OFFPAGE TRUE
J 0
(-450 3175);
DISPLAY 0.872340 (-450 3175);
PAINT GREEN (-450 3175);
DISPLAY INVISIBLE (-450 3175);
FORCEADD OFFPAGE..2
(-775 3250);
FORCEPROP 2 LAST $XR0 138 
J 0
(-586 3250);
DISPLAY 0.638298 (-586 3250);
PAINT MONO (-586 3250);
FORCEPROP 1 LAST COMMENT_BODY TRUE
J 0
(-820 3155);
DISPLAY 0.872340 (-820 3155);
PAINT GREEN (-820 3155);
DISPLAY INVISIBLE (-820 3155);
FORCEPROP 2 LAST CDS_LIB mstr_standard
J 0
(-775 3250);
PAINT ORANGE (-775 3250);
DISPLAY INVISIBLE (-775 3250);
FORCEPROP 2 LAST PATH I55
J 0
(-550 3300);
DISPLAY 1.021277 (-550 3300);
PAINT ORANGE (-550 3300);
DISPLAY INVISIBLE (-550 3300);
FORCEPROP 1 LAST OFFPAGE TRUE
J 0
(-450 3125);
DISPLAY 0.872340 (-450 3125);
PAINT GREEN (-450 3125);
DISPLAY INVISIBLE (-450 3125);
FORCEADD OFFPAGE..4
(-775 3050);
FORCEPROP 2 LAST $XR0 158 
J 0
(-589 3050);
DISPLAY 0.638298 (-589 3050);
PAINT MONO (-589 3050);
FORCEPROP 2 LAST $XR1 145 
J 0
(-469 3050);
DISPLAY 0.638298 (-469 3050);
PAINT MONO (-469 3050);
FORCEPROP 1 LAST COMMENT_BODY TRUE
J 0
(-800 2950);
DISPLAY 1.404255 (-800 2950);
PAINT PEACH (-800 2950);
DISPLAY INVISIBLE (-800 2950);
FORCEPROP 1 LAST OFFPAGE TRUE
J 0
(-450 2925);
DISPLAY 1.404255 (-450 2925);
PAINT GREEN (-450 2925);
DISPLAY INVISIBLE (-450 2925);
FORCEPROP 2 LAST CDS_LIB mstr_standard
J 0
(-775 3050);
PAINT ORANGE (-775 3050);
DISPLAY INVISIBLE (-775 3050);
FORCEPROP 2 LAST PATH I56
J 0
(-600 3125);
DISPLAY 1.021277 (-600 3125);
PAINT ORANGE (-600 3125);
DISPLAY INVISIBLE (-600 3125);
FORCEADD OFFPAGE..2
(-775 3100);
FORCEPROP 2 LAST $XR0 145 
J 0
(-586 3100);
DISPLAY 0.638298 (-586 3100);
PAINT MONO (-586 3100);
FORCEPROP 2 LAST $XR1 158 
J 0
(-466 3100);
DISPLAY 0.638298 (-466 3100);
PAINT MONO (-466 3100);
FORCEPROP 1 LAST COMMENT_BODY TRUE
J 0
(-820 3005);
DISPLAY 1.404255 (-820 3005);
PAINT PEACH (-820 3005);
DISPLAY INVISIBLE (-820 3005);
FORCEPROP 1 LAST OFFPAGE TRUE
J 0
(-450 2975);
PAINT GREEN (-450 2975);
DISPLAY INVISIBLE (-450 2975);
FORCEPROP 2 LAST CDS_LIB mstr_standard
J 0
(-775 3100);
PAINT ORANGE (-775 3100);
DISPLAY INVISIBLE (-775 3100);
FORCEPROP 2 LAST PATH I57
J 0
(-600 3175);
DISPLAY 1.021277 (-600 3175);
PAINT ORANGE (-600 3175);
DISPLAY INVISIBLE (-600 3175);
FORCEADD OFFPAGE..3
(-775 2700);
FORCEPROP 2 LAST $XR0 138 
J 0
(-561 2700);
DISPLAY 0.638298 (-561 2700);
PAINT MONO (-561 2700);
FORCEPROP 1 LAST COMMENT_BODY TRUE
J 0
(-825 2600);
DISPLAY 0.872340 (-825 2600);
PAINT GREEN (-825 2600);
DISPLAY INVISIBLE (-825 2600);
FORCEPROP 2 LAST CDS_LIB mstr_standard
J 0
(-775 2700);
PAINT ORANGE (-775 2700);
DISPLAY INVISIBLE (-775 2700);
FORCEPROP 2 LAST PATH I61
J 0
(-600 2775);
DISPLAY 1.021277 (-600 2775);
PAINT ORANGE (-600 2775);
DISPLAY INVISIBLE (-600 2775);
FORCEPROP 1 LAST OFFPAGE TRUE
J 0
(-450 2575);
DISPLAY 0.872340 (-450 2575);
PAINT GREEN (-450 2575);
DISPLAY INVISIBLE (-450 2575);
FORCEADD OFFPAGE..2
(-775 2200);
FORCEPROP 2 LAST $XR0 133 
J 0
(-586 2200);
DISPLAY 0.638298 (-586 2200);
PAINT MONO (-586 2200);
FORCEPROP 2 LAST $XR1 190 
J 0
(-466 2200);
DISPLAY 0.638298 (-466 2200);
PAINT MONO (-466 2200);
FORCEPROP 1 LAST COMMENT_BODY TRUE
J 0
(-820 2105);
DISPLAY 0.872340 (-820 2105);
PAINT GREEN (-820 2105);
DISPLAY INVISIBLE (-820 2105);
FORCEPROP 2 LAST CDS_LIB mstr_standard
J 0
(-775 2200);
PAINT ORANGE (-775 2200);
DISPLAY INVISIBLE (-775 2200);
FORCEPROP 2 LAST PATH I63
J 0
(-600 2275);
DISPLAY 1.021277 (-600 2275);
PAINT ORANGE (-600 2275);
DISPLAY INVISIBLE (-600 2275);
FORCEPROP 1 LAST OFFPAGE TRUE
J 0
(-450 2075);
DISPLAY 0.872340 (-450 2075);
PAINT GREEN (-450 2075);
DISPLAY INVISIBLE (-450 2075);
FORCEADD OFFPAGE..4
(-775 2000);
FORCEPROP 2 LAST $XR0 156 
J 0
(-589 2000);
DISPLAY 0.638298 (-589 2000);
PAINT MONO (-589 2000);
FORCEPROP 2 LAST CDS_LIB mstr_standard
J 0
(-775 2000);
PAINT ORANGE (-775 2000);
DISPLAY INVISIBLE (-775 2000);
FORCEPROP 1 LAST COMMENT_BODY TRUE
J 0
(-800 1900);
DISPLAY 1.404255 (-800 1900);
PAINT PEACH (-800 1900);
DISPLAY INVISIBLE (-800 1900);
FORCEPROP 1 LAST OFFPAGE TRUE
J 0
(-450 1875);
PAINT GREEN (-450 1875);
DISPLAY INVISIBLE (-450 1875);
FORCEPROP 2 LAST PATH I67
J 0
(-575 2050);
DISPLAY 1.021277 (-575 2050);
PAINT ORANGE (-575 2050);
DISPLAY INVISIBLE (-575 2050);
FORCEADD OFFPAGE..2
R 2
(-6625 3500);
FORCEPROP 2 LAST $XR0 146 
J 0
(-6880 3500);
DISPLAY 0.638298 (-6880 3500);
PAINT MONO (-6880 3500);
FORCEPROP 1 LAST OFFPAGE TRUE
J 2
(-6950 3375);
DISPLAY 0.872340 (-6950 3375);
PAINT GREEN (-6950 3375);
DISPLAY INVISIBLE (-6950 3375);
FORCEPROP 2 LAST CDS_LIB mstr_standard
J 0
(-6625 3500);
PAINT ORANGE (-6625 3500);
DISPLAY INVISIBLE (-6625 3500);
FORCEPROP 1 LAST COMMENT_BODY TRUE
J 2
(-6580 3405);
DISPLAY 0.872340 (-6580 3405);
PAINT PEACH (-6580 3405);
DISPLAY INVISIBLE (-6580 3405);
FORCEPROP 2 LAST PATH I7
J 0
(-6575 3575);
DISPLAY 1.021277 (-6575 3575);
PAINT ORANGE (-6575 3575);
DISPLAY INVISIBLE (-6575 3575);
FORCEADD OFFPAGE..4
R 2
(-7375 3550);
FORCEPROP 2 LAST $XR0 133 
J 0
(-7627 3550);
DISPLAY 0.638298 (-7627 3550);
PAINT MONO (-7627 3550);
FORCEPROP 2 LAST $XR1 146 
J 0
(-7747 3550);
DISPLAY 0.638298 (-7747 3550);
PAINT MONO (-7747 3550);
FORCEPROP 1 LAST OFFPAGE TRUE
J 2
(-7700 3425);
DISPLAY 0.872340 (-7700 3425);
PAINT GREEN (-7700 3425);
DISPLAY INVISIBLE (-7700 3425);
FORCEPROP 1 LAST COMMENT_BODY TRUE
J 2
(-7350 3450);
DISPLAY 0.872340 (-7350 3450);
PAINT GREEN (-7350 3450);
DISPLAY INVISIBLE (-7350 3450);
FORCEPROP 2 LAST CDS_LIB mstr_standard
J 0
(-7375 3550);
PAINT ORANGE (-7375 3550);
DISPLAY INVISIBLE (-7375 3550);
FORCEPROP 2 LAST PATH I8
J 0
(-7325 3625);
DISPLAY 1.021277 (-7325 3625);
PAINT ORANGE (-7325 3625);
DISPLAY INVISIBLE (-7325 3625);
FORCEADD OFFPAGE..5
(-7175 2050);
FORCEPROP 2 LAST $XR0 235 
J 0
(-7460 2050);
DISPLAY 0.638298 (-7460 2050);
PAINT MONO (-7460 2050);
FORCEPROP 1 LAST OFFPAGE TRUE
J 0
(-6850 1925);
PAINT GREEN (-6850 1925);
DISPLAY INVISIBLE (-6850 1925);
FORCEPROP 1 LAST COMMENT_BODY TRUE
J 0
(-7075 1975);
DISPLAY 1.404255 (-7075 1975);
PAINT PEACH (-7075 1975);
DISPLAY INVISIBLE (-7075 1975);
FORCEPROP 2 LAST CDS_LIB mstr_standard
J 0
(-7175 2050);
PAINT ORANGE (-7175 2050);
DISPLAY INVISIBLE (-7175 2050);
FORCEPROP 2 LAST PATH I86
J 0
(-7125 2125);
DISPLAY 1.021277 (-7125 2125);
PAINT ORANGE (-7125 2125);
DISPLAY INVISIBLE (-7125 2125);
FORCEADD OFFPAGE..5
(-7175 2000);
FORCEPROP 2 LAST $XR0 235 
J 0
(-7460 2000);
DISPLAY 0.638298 (-7460 2000);
PAINT MONO (-7460 2000);
FORCEPROP 2 LAST CDS_LIB mstr_standard
J 0
(-7175 2000);
PAINT ORANGE (-7175 2000);
DISPLAY INVISIBLE (-7175 2000);
FORCEPROP 1 LAST OFFPAGE TRUE
J 0
(-6850 1875);
PAINT GREEN (-6850 1875);
DISPLAY INVISIBLE (-6850 1875);
FORCEPROP 1 LAST COMMENT_BODY TRUE
J 0
(-7075 1925);
DISPLAY 1.404255 (-7075 1925);
PAINT PEACH (-7075 1925);
DISPLAY INVISIBLE (-7075 1925);
FORCEPROP 2 LAST PATH I87
J 0
(-7125 2075);
DISPLAY 1.021277 (-7125 2075);
PAINT ORANGE (-7125 2075);
DISPLAY INVISIBLE (-7125 2075);
FORCEADD OFFPAGE..1
(-7175 2150);
FORCEPROP 2 LAST $XR0 135 
J 0
(-7427 2150);
DISPLAY 0.638298 (-7427 2150);
PAINT MONO (-7427 2150);
FORCEPROP 1 LAST OFFPAGE TRUE
J 0
(-6850 2025);
PAINT GREEN (-6850 2025);
DISPLAY INVISIBLE (-6850 2025);
FORCEPROP 2 LAST CDS_LIB mstr_standard
J 0
(-7175 2150);
PAINT ORANGE (-7175 2150);
DISPLAY INVISIBLE (-7175 2150);
FORCEPROP 1 LAST COMMENT_BODY TRUE
J 0
(-7050 2050);
DISPLAY 1.404255 (-7050 2050);
PAINT PEACH (-7050 2050);
DISPLAY INVISIBLE (-7050 2050);
FORCEPROP 2 LAST PATH I88
J 0
(-7125 2225);
DISPLAY 1.021277 (-7125 2225);
PAINT ORANGE (-7125 2225);
DISPLAY INVISIBLE (-7125 2225);
FORCEADD OFFPAGE..4
R 2
(-7375 3600);
FORCEPROP 2 LAST $XR0 133 
J 0
(-7627 3600);
DISPLAY 0.638298 (-7627 3600);
PAINT MONO (-7627 3600);
FORCEPROP 2 LAST $XR1 184 
J 0
(-7747 3600);
DISPLAY 0.638298 (-7747 3600);
PAINT MONO (-7747 3600);
FORCEPROP 1 LAST OFFPAGE TRUE
J 2
(-7700 3475);
DISPLAY 0.872340 (-7700 3475);
PAINT GREEN (-7700 3475);
DISPLAY INVISIBLE (-7700 3475);
FORCEPROP 1 LAST COMMENT_BODY TRUE
J 2
(-7350 3500);
DISPLAY 0.872340 (-7350 3500);
PAINT GREEN (-7350 3500);
DISPLAY INVISIBLE (-7350 3500);
FORCEPROP 2 LAST CDS_LIB mstr_standard
J 0
(-7375 3600);
PAINT ORANGE (-7375 3600);
DISPLAY INVISIBLE (-7375 3600);
FORCEPROP 2 LAST PATH I9
J 0
(-7325 3675);
DISPLAY 1.021277 (-7325 3675);
PAINT ORANGE (-7325 3675);
DISPLAY INVISIBLE (-7325 3675);
FORCEADD OFFPAGE..2
(-775 2650);
FORCEPROP 2 LAST $XR0 138 
J 0
(-586 2650);
DISPLAY 0.638298 (-586 2650);
PAINT MONO (-586 2650);
FORCEPROP 1 LAST COMMENT_BODY TRUE
J 0
(-820 2555);
DISPLAY 0.872340 (-820 2555);
PAINT GREEN (-820 2555);
DISPLAY INVISIBLE (-820 2555);
FORCEPROP 2 LAST CDS_LIB mstr_standard
J 0
(-775 2650);
PAINT ORANGE (-775 2650);
DISPLAY INVISIBLE (-775 2650);
FORCEPROP 2 LAST PATH I95
J 0
(-575 2725);
DISPLAY 1.021277 (-575 2725);
PAINT ORANGE (-575 2725);
DISPLAY INVISIBLE (-575 2725);
FORCEPROP 1 LAST OFFPAGE TRUE
J 0
(-450 2525);
DISPLAY 0.872340 (-450 2525);
PAINT GREEN (-450 2525);
DISPLAY INVISIBLE (-450 2525);
FORCEADD CAD_NOTE..1
(-1525 625);
FORCEPROP 0 LAST L1 PLEASE PLACE LED NEAR POWER BUTTON S9A2
J 0
(-1700 500);
DISPLAY 1.021277 (-1700 500);
PAINT ORANGE (-1700 500);
FORCEPROP 2 LAST CDS_LIB mstr_symbols
J 0
(-1525 625);
PAINT MONO (-1525 625);
DISPLAY INVISIBLE (-1525 625);
FORCEPROP 1 LAST COMMENT_BODY TRUE
J 0
(-1500 725);
DISPLAY 0.978723 (-1500 725);
PAINT ORANGE (-1500 725);
DISPLAY INVISIBLE (-1500 725);
FORCEADD CAD_NOTE..1
(-7700 4800);
FORCEPROP 0 LAST L1 PLACE DAMPENING RESISTOR ON LPC CLOCK CLOSE TO PCH
J 0
(-7825 4675);
DISPLAY 1.021277 (-7825 4675);
PAINT ORANGE (-7825 4675);
FORCEPROP 2 LAST CDS_LIB mstr_symbols
J 0
(-7700 4800);
PAINT ORANGE (-7700 4800);
DISPLAY INVISIBLE (-7700 4800);
FORCEPROP 1 LAST COMMENT_BODY TRUE
J 0
(-7675 4900);
DISPLAY 0.978723 (-7675 4900);
PAINT ORANGE (-7675 4900);
DISPLAY INVISIBLE (-7675 4900);
FORCEADD CAD_NOTE..1
(-1200 4750);
FORCEPROP 0 LAST L1 PLACE SERIES TERM RES CLOSE TO PCH
J 0
(-1350 4625);
DISPLAY 0.808511 (-1350 4625);
PAINT ORANGE (-1350 4625);
FORCEPROP 2 LAST CDS_LIB mstr_symbols
J 0
(-1200 4750);
PAINT MONO (-1200 4750);
DISPLAY INVISIBLE (-1200 4750);
FORCEPROP 1 LAST COMMENT_BODY TRUE
J 0
(-1175 4850);
DISPLAY 0.978723 (-1175 4850);
PAINT ORANGE (-1175 4850);
DISPLAY INVISIBLE (-1175 4850);
FORCEADD DNS..2
(-1420 4095);
PAINT RED (-1420 4095);
FORCEPROP 1 LAST COMMENT_BODY TRUE
R 1
J 0
(-1345 3870);
DISPLAY 0.872340 (-1345 3870);
PAINT GREEN (-1345 3870);
DISPLAY INVISIBLE (-1345 3870);
FORCEPROP 2 LAST CDS_LIB mstr_misc
J 0
(-1420 4095);
PAINT ORANGE (-1420 4095);
DISPLAY INVISIBLE (-1420 4095);
FORCEADD DESIGN_NOTE..1
(-6400 225);
FORCEPROP 0 LAST L1 SMBUS PULL UP AND SERIES RESISTORS ON SEPARATE PAGE
J 0
(-6575 75);
DISPLAY 1.021277 (-6575 75);
PAINT ORANGE (-6575 75);
FORCEPROP 2 LAST CDS_LIB mstr_symbols
J 0
(-6400 225);
PAINT ORANGE (-6400 225);
DISPLAY INVISIBLE (-6400 225);
FORCEPROP 1 LAST COMMENT_BODY TRUE
J 0
(-6375 325);
DISPLAY 0.978723 (-6375 325);
PAINT ORANGE (-6375 325);
DISPLAY INVISIBLE (-6375 325);
FORCEADD INTEL_CORP_BPAGE..1
(0 0);
FORCEPROP 1 LAST CDS_CON_LAST_MODIFIED Tue Dec 01 11:51:57 2015
J 0
(-1425 325);
DISPLAY 1.340426 (-1425 325);
PAINT ORANGE (-1425 325);
DISPLAY INVISIBLE (-1425 325);
FORCEPROP 1 LAST CUSTOM_TXT_CDS <CURRENT_DESIGN_SHEET> OF <TOTAL_DESIGN_SHEETS>
J 0
(-500 25);
PAINT GREEN (-500 25);
FORCEPROP 1 LAST CUSTOM_TXT_CDS <CON_LAST_MODIFIED>
J 0
(-1925 350);
PAINT GREEN (-1925 350);
FORCEPROP 2 LAST CUSTOM_TXT_CDS <XR_PAGE_TITLE>
J 0
(-7890 5250);
DISPLAY 0.638298 (-7890 5250);
PAINT PINK (-7890 5250);
DISPLAY INVISIBLE (-7890 5250);
FORCEPROP 1 LAST SCH_TITLE LEWISBURG 6/11 GPIO A-D
J 0
(-7950 50);
DISPLAY 1.212766 (-7950 50);
PAINT YELLOW (-7950 50);
FORCEPROP 1 LAST SCH_ADDRESS3 Santa Clara, CA 95052-8119
J 0
(-3975 25);
DISPLAY 0.617021 (-3975 25);
PAINT YELLOW (-3975 25);
FORCEPROP 1 LAST SCH_ADDRESS2 P.O. BOX 58119
J 0
(-3975 75);
DISPLAY 0.617021 (-3975 75);
PAINT YELLOW (-3975 75);
FORCEPROP 1 LAST SCH_ADDRESS1 2200 Mission College Blvd.
J 0
(-3975 125);
DISPLAY 0.617021 (-3975 125);
PAINT YELLOW (-3975 125);
FORCEPROP 1 LAST SCH_REV 2.420
J 0
(-250 150);
DISPLAY 0.978723 (-250 150);
PAINT YELLOW (-250 150);
FORCEPROP 1 LAST SCH_DEPT BESD
J 1
(-4450 100);
DISPLAY 1.212766 (-4450 100);
PAINT YELLOW (-4450 100);
FORCEPROP 1 LAST SCH_NUMBER H4694802
J 0
(-1300 150);
DISPLAY 1.212766 (-1300 150);
PAINT YELLOW (-1300 150);
FORCEPROP 2 LAST PAGE_BORDER TRUE
J 0
(-7890 5250);
DISPLAY 0.851064 (-7890 5250);
PAINT PINK (-7890 5250);
DISPLAY INVISIBLE (-7890 5250);
FORCEPROP 2 LAST CDS_LIB mstr_symbols
J 0
(0 0);
PAINT ORANGE (0 0);
DISPLAY INVISIBLE (0 0);
FORCEPROP 1 LAST COMMENT_BODY TRUE
J 0
(12 12);
DISPLAY 0.638298 (12 12);
PAINT PEACH (12 12);
DISPLAY INVISIBLE (12 12);
FORCEPROP 2 LAST CDS_XR_PAGE_TITLE CR-119 : @BASEBOARD_FAB2_LIB.BASEBOARD_FAB2(SCH_1):PAGE119
J 0
(-7890 5250);
DISPLAY 0.638298 (-7890 5250);
PAINT PINK (-7890 5250);
DISPLAY INVISIBLE (-7890 5250);
WIRE 16 -1 (-500 1700)(-500 1575);
WIRE 16 -1 (-500 1575)(-600 1575);
WIRE 16 -1 (-1750 950)(-1750 1050);
WIRE 16 -1 (-2525 1375)(-2525 1500);
WIRE 16 -1 (-2525 1500)(-2525 1550);
WIRE 16 -1 (-2525 525)(-2525 575);
WIRE 16 -1 (-2975 1150)(-2975 1050);
WIRE 16 -1 (-1700 4850)(-1700 4825);
WIRE 16 -1 (-7125 2150)(-6000 2150);
FORCEPROP 2 LAST SIG_NAME FM_QAT_EN_N
J 0
(-7100 2160);
DISPLAY 0.617021 (-7100 2160);
PAINT ORANGE (-7100 2160);
WIRE 16 -1 (-7125 2450)(-6000 2450);
FORCEPROP 0 LAST SIG_NAME FM_PWR_BTN_N
J 0
(-7100 2460);
DISPLAY 0.617021 (-7100 2460);
PAINT ORANGE (-7100 2460);
WIRE 16 -1 (-7125 2550)(-6000 2550);
FORCEPROP 2 LAST SIG_NAME FM_PMBUS_ALERT_BUF_EN_N
J 0
(-7100 2560);
DISPLAY 0.617021 (-7100 2560);
PAINT ORANGE (-7100 2560);
WIRE 16 -1 (-7125 2700)(-6000 2700);
FORCEPROP 2 LAST SIG_NAME FM_BIOS_TOP_SWAP_SPKR
J 0
(-7100 2710);
DISPLAY 0.617021 (-7100 2710);
PAINT ORANGE (-7100 2710);
WIRE 16 -1 (-7125 2850)(-6000 2850);
FORCEPROP 0 LAST SIG_NAME FM_PCH_PWRBTN_OUT_N
J 0
(-7100 2860);
DISPLAY 0.617021 (-7100 2860);
PAINT ORANGE (-7100 2860);
WIRE 16 -1 (-7125 2900)(-6000 2900);
FORCEPROP 2 LAST SIG_NAME FM_UV_ADR_TRIGGER_EN
J 0
(-7100 2910);
DISPLAY 0.617021 (-7100 2910);
PAINT ORANGE (-7100 2910);
WIRE 16 -1 (-7125 2950)(-6000 2950);
FORCEPROP 2 LAST SIG_NAME FM_BIOS_PREFRB2_GOOD
J 0
(-7100 2960);
DISPLAY 0.617021 (-7100 2960);
PAINT ORANGE (-7100 2960);
WIRE 16 -1 (-7125 3000)(-6000 3000);
FORCEPROP 2 LAST SIG_NAME FM_BIOS_POST_CMPLT_N
J 0
(-7100 3010);
DISPLAY 0.617021 (-7100 3010);
PAINT ORANGE (-7100 3010);
WIRE 16 -1 (-7125 3050)(-6000 3050);
FORCEPROP 2 LAST SIG_NAME FM_FAST_PROCHOT_EN_N
J 0
(-7100 3060);
DISPLAY 0.617021 (-7100 3060);
PAINT ORANGE (-7100 3060);
WIRE 16 -1 (-7125 3100)(-6000 3100);
FORCEPROP 2 LAST SIG_NAME FM_USB_P0_EN_BOOT_BIOS_STRAP_N
J 0
(-7100 3110);
DISPLAY 0.617021 (-7100 3110);
PAINT ORANGE (-7100 3110);
WIRE 16 -1 (-7325 3250)(-6000 3250);
FORCEPROP 0 LAST SIG_NAME PU_FM_RCIN_N
J 0
(-7300 3261);
DISPLAY 0.617021 (-7300 3261);
PAINT ORANGE (-7300 3261);
WIRE 16 -1 (-6925 3350)(-6000 3350);
FORCEPROP 0 LAST SIG_NAME LPC_LAD1_IO1
J 2
(-6100 3361);
DISPLAY 0.617021 (-6100 3361);
PAINT ORANGE (-6100 3361);
FORCEPROP 2 LASTPROP $XRERR UNIQUE?
J 0
(-6340 3361);
DISPLAY 0.638298 (-6340 3361);
PAINT MONO (-6340 3361);
DISPLAY INVISIBLE (-6340 3361);
WIRE 16 -1 (-6925 3450)(-6000 3450);
FORCEPROP 0 LAST SIG_NAME LPC_LAD3_IO3
J 2
(-6100 3461);
DISPLAY 0.617021 (-6100 3461);
PAINT ORANGE (-6100 3461);
FORCEPROP 2 LASTPROP $XRERR UNIQUE?
J 0
(-6340 3461);
DISPLAY 0.638298 (-6340 3461);
PAINT MONO (-6340 3461);
DISPLAY INVISIBLE (-6340 3461);
WIRE 16 -1 (-7325 3800)(-6000 3800);
FORCEPROP 0 LAST SIG_NAME PU_LPC_PME_N
J 0
(-7325 3811);
DISPLAY 0.617021 (-7325 3811);
PAINT ORANGE (-7325 3811);
WIRE 16 -1 (-7325 4000)(-6000 4000);
FORCEPROP 0 LAST SIG_NAME FM_MB_SLOT_ID2
J 0
(-7325 4010);
DISPLAY 0.617021 (-7325 4010);
PAINT ORANGE (-7325 4010);
WIRE 16 -1 (-7325 4400)(-6000 4400);
FORCEPROP 2 LAST SIG_NAME FM_BMC_READY_N
J 0
(-7325 4410);
DISPLAY 0.617021 (-7325 4410);
PAINT ORANGE (-7325 4410);
WIRE 16 -1 (-1700 4625)(-1700 4100);
WIRE 16 -1 (-1700 4100)(-1525 4100);
WIRE 16 -1 (-2400 4100)(-1700 4100);
FORCEPROP 2 LAST SIG_NAME FM_SLT_CFG2_R
J 0
(-2250 4110);
DISPLAY 0.617021 (-2250 4110);
PAINT ORANGE (-2250 4110);
FORCEPROP 2 LASTPROP $XRERR UNIQUE?
J 0
(-2490 4110);
DISPLAY 0.638298 (-2490 4110);
PAINT MONO (-2490 4110);
DISPLAY INVISIBLE (-2490 4110);
WIRE 16 -1 (-2400 4300)(-825 4300);
FORCEPROP 2 LAST SIG_NAME FM_BIOS_POST_CMPLT_N
J 0
(-2250 4310);
DISPLAY 0.617021 (-2250 4310);
PAINT ORANGE (-2250 4310);
WIRE 16 -1 (-2400 4050)(-825 4050);
FORCEPROP 2 LAST SIG_NAME FM_SLT_CFG1
J 0
(-2250 4060);
DISPLAY 0.617021 (-2250 4060);
PAINT ORANGE (-2250 4060);
WIRE 16 -1 (-2400 3750)(-825 3750);
FORCEPROP 2 LAST SIG_NAME FM_PCH_SATA_RAID_KEY
J 0
(-2250 3760);
DISPLAY 0.617021 (-2250 3760);
PAINT ORANGE (-2250 3760);
WIRE 16 -1 (-2400 3450)(-825 3450);
FORCEPROP 2 LAST SIG_NAME SMB_SMLINK0_STBY_LVC3_SDA_R1
J 0
(-2250 3460);
DISPLAY 0.617021 (-2250 3460);
PAINT ORANGE (-2250 3460);
WIRE 16 -1 (-2400 3400)(-825 3400);
FORCEPROP 2 LAST SIG_NAME SMB_SMLINK0_STBY_LVC3_SCL_R1
J 0
(-2250 3410);
DISPLAY 0.617021 (-2250 3410);
PAINT ORANGE (-2250 3410);
WIRE 16 -1 (-7325 4350)(-6000 4350);
FORCEPROP 2 LAST SIG_NAME FM_TPM_PRES_N
J 0
(-7325 4360);
DISPLAY 0.617021 (-7325 4360);
PAINT ORANGE (-7325 4360);
WIRE 16 -1 (-7325 4300)(-6000 4300);
FORCEPROP 2 LAST SIG_NAME FM_OCP_MEZZA_PRES_N
J 0
(-7325 4310);
DISPLAY 0.617021 (-7325 4310);
PAINT ORANGE (-7325 4310);
WIRE 16 -1 (-7325 4250)(-6000 4250);
FORCEPROP 2 LAST SIG_NAME FM_POST_CARD_PRES_BMC_N
J 0
(-7325 4260);
DISPLAY 0.617021 (-7325 4260);
PAINT ORANGE (-7325 4260);
WIRE 16 -1 (-7325 4150)(-6000 4150);
FORCEPROP 2 LAST SIG_NAME RST_PCH_SYSRST_BTN_OUT_N
J 0
(-7325 4160);
DISPLAY 0.617021 (-7325 4160);
PAINT ORANGE (-7325 4160);
WIRE 16 -1 (-6575 3500)(-6000 3500);
FORCEPROP 0 LAST SIG_NAME LPC_LFRAME_N_CS0_N
J 0
(-6585 3510);
DISPLAY 0.617021 (-6585 3510);
PAINT ORANGE (-6585 3510);
WIRE 16 -1 (-7125 3150)(-6000 3150);
FORCEPROP 2 LAST SIG_NAME FM_PCH_BMC_THERMTRIP_EXI_STRAP_N
J 0
(-7100 3160);
DISPLAY 0.617021 (-7100 3160);
PAINT ORANGE (-7100 3160);
WIRE 16 -1 (-7125 2800)(-6000 2800);
FORCEPROP 2 LAST SIG_NAME IRQ_PCH_NIC_ALERT_N
J 0
(-7100 2810);
DISPLAY 0.617021 (-7100 2810);
PAINT ORANGE (-7100 2810);
WIRE 16 -1 (-7125 2100)(-6000 2100);
FORCEPROP 2 LAST SIG_NAME PU_IRQ_VRALERT_N
J 0
(-7100 2110);
DISPLAY 0.617021 (-7100 2110);
PAINT ORANGE (-7100 2110);
WIRE 16 -1 (-1450 4400)(-825 4400);
FORCEPROP 0 LAST SIG_NAME FM_CPU_CATERR_DLY_LVT3_N
J 2
(-900 4410);
DISPLAY 0.617021 (-900 4410);
PAINT ORANGE (-900 4410);
WIRE 16 -1 (-1325 4100)(-825 4100);
FORCEPROP 2 LAST SIG_NAME FM_PWRBRK_SLOT_N
J 2
(-900 4110);
DISPLAY 0.617021 (-900 4110);
PAINT ORANGE (-900 4110);
WIRE 16 -1 (-2400 4400)(-1650 4400);
FORCEPROP 2 LAST SIG_NAME FM_CPU_CATERR_DLY_LVT3_R_N
J 0
(-2250 4410);
DISPLAY 0.617021 (-2250 4410);
PAINT ORANGE (-2250 4410);
FORCEPROP 2 LASTPROP $XRERR UNIQUE?
J 0
(-2490 4410);
DISPLAY 0.638298 (-2490 4410);
PAINT MONO (-2490 4410);
DISPLAY INVISIBLE (-2490 4410);
WIRE 16 -1 (-2400 4250)(-825 4250);
FORCEPROP 2 LAST SIG_NAME FM_THROTTLE_N
J 0
(-2250 4260);
DISPLAY 0.617021 (-2250 4260);
PAINT ORANGE (-2250 4260);
WIRE 16 -1 (-2400 4200)(-825 4200);
FORCEPROP 2 LAST SIG_NAME FM_BB_BMC_MP_GPIO
J 0
(-2250 4210);
DISPLAY 0.617021 (-2250 4210);
PAINT ORANGE (-2250 4210);
WIRE 16 -1 (-2400 4150)(-825 4150);
FORCEPROP 2 LAST SIG_NAME FM_PMBUS_ALERT_BUF_EN_N
J 0
(-2250 4160);
DISPLAY 0.617021 (-2250 4160);
PAINT ORANGE (-2250 4160);
WIRE 16 -1 (-2400 4350)(-825 4350);
FORCEPROP 2 LAST SIG_NAME IRQ_BMC_PCH_SMI_LPC_N
J 0
(-2250 4360);
DISPLAY 0.617021 (-2250 4360);
PAINT ORANGE (-2250 4360);
WIRE 16 -1 (-1350 2200)(-825 2200);
FORCEPROP 0 LAST SIG_NAME FM_PCH_PLD_DATA
J 0
(-1260 2210);
DISPLAY 0.617021 (-1260 2210);
PAINT ORANGE (-1260 2210);
WIRE 16 -1 (-1375 2950)(-825 2950);
FORCEPROP 0 LAST SIG_NAME FM_ADR_MODE_SEL
J 0
(-1285 2960);
DISPLAY 0.617021 (-1285 2960);
PAINT ORANGE (-1285 2960);
WIRE 16 -1 (-800 1575)(-1250 1575);
FORCEPROP 2 LAST SIG_NAME FM_PWR_LED_A
J 0
(-1160 1585);
DISPLAY 0.617021 (-1160 1585);
PAINT ORANGE (-1160 1585);
FORCEPROP 2 LASTPROP $XRERR UNIQUE?
J 0
(-1400 1585);
DISPLAY 0.638298 (-1400 1585);
PAINT MONO (-1400 1585);
DISPLAY INVISIBLE (-1400 1585);
WIRE 16 -1 (-1450 1575)(-1750 1575);
FORCEPROP 2 LAST SIG_NAME FM_PWR_LED_K
J 0
(-1960 1585);
DISPLAY 0.617021 (-1960 1585);
PAINT ORANGE (-1960 1585);
FORCEPROP 2 LASTPROP $XRERR UNIQUE?
J 0
(-2200 1585);
DISPLAY 0.638298 (-2200 1585);
PAINT MONO (-2200 1585);
DISPLAY INVISIBLE (-2200 1585);
WIRE 16 -1 (-1750 1575)(-1750 1450);
WIRE 16 -1 (-2525 1150)(-1950 1150);
FORCEPROP 2 LAST SIG_NAME FM_PWR_LED
J 0
(-2385 1160);
DISPLAY 0.617021 (-2385 1160);
PAINT ORANGE (-2385 1160);
FORCEPROP 2 LASTPROP $XRERR UNIQUE?
J 0
(-2625 1160);
DISPLAY 0.638298 (-2625 1160);
PAINT MONO (-2625 1160);
DISPLAY INVISIBLE (-2625 1160);
WIRE 16 -1 (-2525 1150)(-2525 1300);
WIRE 16 -1 (-2525 975)(-2525 1150);
WIRE 16 -1 (-2400 2600)(-1825 2600);
FORCEPROP 2 LAST SIG_NAME TP_PCH_GPP_D12
J 0
(-2250 2610);
DISPLAY 0.617021 (-2250 2610);
PAINT ORANGE (-2250 2610);
FORCEPROP 2 LASTPROP $XRERR UNIQUE?
J 0
(-1795 2600);
DISPLAY 0.638298 (-1795 2600);
PAINT MONO (-1795 2600);
DISPLAY INVISIBLE (-1795 2600);
WIRE 16 -1 (-2400 2200)(-1550 2200);
FORCEPROP 2 LAST SIG_NAME FM_PCH_PLD_DATA_R
J 0
(-2250 2210);
DISPLAY 0.617021 (-2250 2210);
PAINT ORANGE (-2250 2210);
FORCEPROP 2 LASTPROP $XRERR UNIQUE?
J 0
(-2490 2210);
DISPLAY 0.638298 (-2490 2210);
PAINT MONO (-2490 2210);
DISPLAY INVISIBLE (-2490 2210);
WIRE 16 -1 (-2400 2650)(-825 2650);
FORCEPROP 2 LAST SIG_NAME SMB_SLOTX24_STBY_LVC3_SCL_R1
J 0
(-2250 2660);
DISPLAY 0.617021 (-2250 2660);
PAINT ORANGE (-2250 2660);
WIRE 16 -1 (-2400 2000)(-825 2000);
FORCEPROP 2 LAST SIG_NAME IRQ_BMC_PCH_NMI_STBY_R_N
J 0
(-2250 2010);
DISPLAY 0.617021 (-2250 2010);
PAINT ORANGE (-2250 2010);
WIRE 16 -1 (-2400 2700)(-825 2700);
FORCEPROP 2 LAST SIG_NAME SMB_SLOTX24_STBY_LVC3_SDA_R1
J 0
(-2250 2710);
DISPLAY 0.617021 (-2250 2710);
PAINT ORANGE (-2250 2710);
WIRE 16 -1 (-2400 3850)(-825 3850);
FORCEPROP 2 LAST SIG_NAME FM_BOARD_REV_ID0
J 0
(-2250 3860);
DISPLAY 0.617021 (-2250 3860);
PAINT ORANGE (-2250 3860);
WIRE 16 -1 (-2400 4000)(-825 4000);
FORCEPROP 2 LAST SIG_NAME FM_SLT_CFG0
J 0
(-2250 4010);
DISPLAY 0.617021 (-2250 4010);
PAINT ORANGE (-2250 4010);
WIRE 16 -1 (-2400 2300)(-825 2300);
FORCEPROP 2 LAST SIG_NAME FM_CPLD_BMC_PWRDN_N
J 0
(-2250 2310);
DISPLAY 0.617021 (-2250 2310);
PAINT ORANGE (-2250 2310);
WIRE 16 -1 (-2400 2050)(-825 2050);
FORCEPROP 2 LAST SIG_NAME FM_PWR_LED_N
J 0
(-2250 2060);
DISPLAY 0.617021 (-2250 2060);
PAINT ORANGE (-2250 2060);
WIRE 16 -1 (-2400 2800)(-825 2800);
FORCEPROP 2 LAST SIG_NAME IRQ_OOB_MGMT_RISER_ALERT_N
J 0
(-2250 2810);
DISPLAY 0.617021 (-2250 2810);
PAINT ORANGE (-2250 2810);
WIRE 16 -1 (-2400 2550)(-825 2550);
FORCEPROP 2 LAST SIG_NAME IRQ_LOM_ALERT_N
J 0
(-2250 2560);
DISPLAY 0.617021 (-2250 2560);
PAINT ORANGE (-2250 2560);
WIRE 16 -1 (-2400 2350)(-825 2350);
FORCEPROP 2 LAST SIG_NAME FM_BMC_CPLD_GPO
J 0
(-2250 2360);
DISPLAY 0.617021 (-2250 2360);
PAINT ORANGE (-2250 2360);
WIRE 16 -1 (-2400 2750)(-825 2750);
FORCEPROP 2 LAST SIG_NAME SGPIO_PCH_SSATA_DOUT0
J 0
(-2250 2760);
DISPLAY 0.617021 (-2250 2760);
PAINT ORANGE (-2250 2760);
WIRE 16 -1 (-2400 2450)(-825 2450);
FORCEPROP 2 LAST SIG_NAME IRQ_FORCE_NM_THROTTLE_N
J 0
(-2250 2460);
DISPLAY 0.617021 (-2250 2460);
PAINT ORANGE (-2250 2460);
WIRE 16 -1 (-2400 2400)(-825 2400);
FORCEPROP 2 LAST SIG_NAME FM_BMC_FAULT_LED_N
J 0
(-2250 2410);
DISPLAY 0.617021 (-2250 2410);
PAINT ORANGE (-2250 2410);
WIRE 16 -1 (-2400 2500)(-825 2500);
FORCEPROP 2 LAST SIG_NAME H_CPU0_FAST_WAKE_LVT3_N
J 0
(-2250 2510);
DISPLAY 0.617021 (-2250 2510);
PAINT ORANGE (-2250 2510);
WIRE 16 -1 (-2400 2250)(-825 2250);
FORCEPROP 2 LAST SIG_NAME FM_BMC_ENABLE_N
J 0
(-2250 2260);
DISPLAY 0.617021 (-2250 2260);
PAINT ORANGE (-2250 2260);
WIRE 16 -1 (-2400 2150)(-825 2150);
FORCEPROP 2 LAST SIG_NAME IRQ_MEZZ_LAN_ALERT_N
J 0
(-2250 2160);
DISPLAY 0.617021 (-2250 2160);
PAINT ORANGE (-2250 2160);
WIRE 16 -1 (-2400 2100)(-825 2100);
FORCEPROP 2 LAST SIG_NAME IRQ_HSC_FAULT_N
J 0
(-2250 2110);
DISPLAY 0.617021 (-2250 2110);
PAINT ORANGE (-2250 2110);
WIRE 16 -1 (-2400 2850)(-825 2850);
FORCEPROP 2 LAST SIG_NAME FM_XRC_PRESENT_N
J 0
(-2250 2860);
DISPLAY 0.617021 (-2250 2860);
PAINT ORANGE (-2250 2860);
WIRE 16 -1 (-2400 3150)(-825 3150);
FORCEPROP 2 LAST SIG_NAME FM_CPU0_THERMTRIP_LATCH_LVT3_N
J 0
(-2250 3160);
DISPLAY 0.617021 (-2250 3160);
PAINT ORANGE (-2250 3160);
WIRE 16 -1 (-2400 3100)(-825 3100);
FORCEPROP 2 LAST SIG_NAME SP2_BMC_CM_UART_TX
J 0
(-2250 3110);
DISPLAY 0.617021 (-2250 3110);
PAINT ORANGE (-2250 3110);
WIRE 16 -1 (-2400 3050)(-825 3050);
FORCEPROP 2 LAST SIG_NAME SP2_BMC_CM_UART_RX
J 0
(-2250 3060);
DISPLAY 0.617021 (-2250 3060);
PAINT ORANGE (-2250 3060);
WIRE 16 -1 (-2400 3000)(-825 3000);
FORCEPROP 2 LAST SIG_NAME FM_BMC_HEARTBEAT_N
J 0
(-2250 3010);
DISPLAY 0.617021 (-2250 3010);
PAINT ORANGE (-2250 3010);
WIRE 16 -1 (-2400 2950)(-1575 2950);
FORCEPROP 2 LAST SIG_NAME FM_ADR_MODE_SEL_R
J 0
(-2250 2960);
DISPLAY 0.617021 (-2250 2960);
PAINT ORANGE (-2250 2960);
FORCEPROP 2 LASTPROP $XRERR UNIQUE?
J 0
(-2490 2960);
DISPLAY 0.638298 (-2490 2960);
PAINT MONO (-2490 2960);
DISPLAY INVISIBLE (-2490 2960);
WIRE 16 -1 (-2400 2900)(-825 2900);
FORCEPROP 2 LAST SIG_NAME FM_XRC_READY_N
J 0
(-2250 2910);
DISPLAY 0.617021 (-2250 2910);
PAINT ORANGE (-2250 2910);
WIRE 16 -1 (-2400 3250)(-825 3250);
FORCEPROP 2 LAST SIG_NAME SMB_HOST_STBY_LVC3_SCL_R1
J 0
(-2250 3260);
DISPLAY 0.617021 (-2250 3260);
PAINT ORANGE (-2250 3260);
WIRE 16 -1 (-2400 3300)(-825 3300);
FORCEPROP 2 LAST SIG_NAME SMB_HOST_STBY_LVC3_SDA_R1
J 0
(-2250 3310);
DISPLAY 0.617021 (-2250 3310);
PAINT ORANGE (-2250 3310);
WIRE 16 -1 (-2400 3600)(-825 3600);
FORCEPROP 2 LAST SIG_NAME SMB_PMBUS_BMC_STBY_LVC3_SDA_R1
J 0
(-2250 3610);
DISPLAY 0.617021 (-2250 3610);
PAINT ORANGE (-2250 3610);
WIRE 16 -1 (-2400 3500)(-825 3500);
FORCEPROP 2 LAST SIG_NAME IRQ_SML0_ALERT_N
J 0
(-2250 3510);
DISPLAY 0.617021 (-2250 3510);
PAINT ORANGE (-2250 3510);
WIRE 16 -1 (-2400 3350)(-825 3350);
FORCEPROP 2 LAST SIG_NAME PU_PCH_TLS_ENABLE_STRAP
J 0
(-2250 3360);
DISPLAY 0.617021 (-2250 3360);
PAINT ORANGE (-2250 3360);
WIRE 16 -1 (-2400 3550)(-825 3550);
FORCEPROP 2 LAST SIG_NAME SMB_PMBUS_BMC_STBY_LVC3_SCL_R1
J 0
(-2250 3560);
DISPLAY 0.617021 (-2250 3560);
PAINT ORANGE (-2250 3560);
WIRE 16 -1 (-2400 3650)(-825 3650);
FORCEPROP 2 LAST SIG_NAME FM_PASSWORD_CLEAR_N
J 0
(-2250 3660);
DISPLAY 0.617021 (-2250 3660);
PAINT ORANGE (-2250 3660);
WIRE 16 -1 (-2400 3700)(-825 3700);
FORCEPROP 2 LAST SIG_NAME FM_CPU1_RC_EN
J 0
(-2250 3710);
DISPLAY 0.617021 (-2250 3710);
PAINT ORANGE (-2250 3710);
WIRE 16 -1 (-2400 3800)(-825 3800);
FORCEPROP 2 LAST SIG_NAME FM_BOARD_REV_ID2
J 0
(-2250 3810);
DISPLAY 0.617021 (-2250 3810);
PAINT ORANGE (-2250 3810);
WIRE 16 -1 (-2400 3900)(-825 3900);
FORCEPROP 2 LAST SIG_NAME FM_BOARD_REV_ID1
J 0
(-2250 3910);
DISPLAY 0.617021 (-2250 3910);
PAINT ORANGE (-2250 3910);
WIRE 16 -1 (-2400 3950)(-825 3950);
FORCEPROP 2 LAST SIG_NAME IRQ_BMC_PCH_SCI_LPC_N
J 0
(-2250 3960);
DISPLAY 0.617021 (-2250 3960);
PAINT ORANGE (-2250 3960);
WIRE 16 -1 (-2975 850)(-2975 675);
WIRE 16 -1 (-2725 675)(-2975 675);
WIRE 16 -1 (-3350 675)(-2975 675);
FORCEPROP 2 LAST SIG_NAME FM_PWR_LED_N
J 0
(-3310 685);
DISPLAY 0.617021 (-3310 685);
PAINT ORANGE (-3310 685);
WIRE 16 -1 (-7325 4200)(-6000 4200);
FORCEPROP 0 LAST SIG_NAME FM_ME_RECOVER_N
J 0
(-7325 4211);
DISPLAY 0.617021 (-7325 4211);
PAINT ORANGE (-7325 4211);
WIRE 16 -1 (-7325 4100)(-6000 4100);
FORCEPROP 0 LAST SIG_NAME FM_CPU_BMC_INIT
J 0
(-7325 4111);
DISPLAY 0.617021 (-7325 4111);
PAINT ORANGE (-7325 4111);
WIRE 16 -1 (-7325 4050)(-6000 4050);
FORCEPROP 0 LAST SIG_NAME FM_UART_PRES_N
J 0
(-7325 4061);
DISPLAY 0.617021 (-7325 4061);
PAINT ORANGE (-7325 4061);
WIRE 16 -1 (-6925 3300)(-6000 3300);
FORCEPROP 0 LAST SIG_NAME LPC_LAD0_IO0
J 2
(-6100 3311);
DISPLAY 0.617021 (-6100 3311);
PAINT ORANGE (-6100 3311);
FORCEPROP 2 LASTPROP $XRERR UNIQUE?
J 0
(-6340 3311);
DISPLAY 0.638298 (-6340 3311);
PAINT MONO (-6340 3311);
DISPLAY INVISIBLE (-6340 3311);
WIRE 16 -1 (-6925 3400)(-6000 3400);
FORCEPROP 0 LAST SIG_NAME LPC_LAD2_IO2
J 2
(-6100 3411);
DISPLAY 0.617021 (-6100 3411);
PAINT ORANGE (-6100 3411);
FORCEPROP 2 LASTPROP $XRERR UNIQUE?
J 0
(-6340 3411);
DISPLAY 0.638298 (-6340 3411);
PAINT MONO (-6340 3411);
DISPLAY INVISIBLE (-6340 3411);
WIRE 16 -1 (-6650 3700)(-6000 3700);
FORCEPROP 2 LAST SIG_NAME CLK_24M_BMC_LPC_R
J 0
(-6485 3710);
DISPLAY 0.617021 (-6485 3710);
PAINT ORANGE (-6485 3710);
FORCEPROP 2 LASTPROP $XRERR UNIQUE?
J 0
(-6725 3710);
DISPLAY 0.638298 (-6725 3710);
PAINT MONO (-6725 3710);
DISPLAY INVISIBLE (-6725 3710);
WIRE 16 -1 (-7325 3600)(-6000 3600);
FORCEPROP 0 LAST SIG_NAME IRQ_PIRQA_SPI_TPM_N
J 0
(-7325 3611);
DISPLAY 0.617021 (-7325 3611);
PAINT ORANGE (-7325 3611);
WIRE 16 -1 (-7125 2000)(-6000 2000);
FORCEPROP 2 LAST SIG_NAME VID_PCH_CORE_PVNN_AUX_VID_0
J 0
(-7100 2010);
DISPLAY 0.617021 (-7100 2010);
PAINT ORANGE (-7100 2010);
WIRE 16 -1 (-7125 2050)(-6000 2050);
FORCEPROP 2 LAST SIG_NAME VID_PCH_CORE_PVNN_AUX_VID_1
J 0
(-7100 2060);
DISPLAY 0.617021 (-7100 2060);
PAINT ORANGE (-7100 2060);
WIRE 16 -1 (-7325 3550)(-6000 3550);
FORCEPROP 0 LAST SIG_NAME IRQ_LPC_SERIRQ_N
J 0
(-7325 3561);
DISPLAY 0.617021 (-7325 3561);
PAINT ORANGE (-7325 3561);
WIRE 16 -1 (-7125 2650)(-6000 2650);
FORCEPROP 2 LAST SIG_NAME RST_PLTRST_N
J 0
(-7100 2660);
DISPLAY 0.617021 (-7100 2660);
PAINT ORANGE (-7100 2660);
WIRE 16 -1 (-7125 2600)(-6000 2600);
FORCEPROP 2 LAST SIG_NAME FM_GLOBAL_RST_WARN_N
J 0
(-7100 2610);
DISPLAY 0.617021 (-7100 2610);
PAINT ORANGE (-7100 2610);
WIRE 16 -1 (-7125 2750)(-6000 2750);
FORCEPROP 2 LAST SIG_NAME FM_UART_ALERT_N
J 0
(-7100 2760);
DISPLAY 0.617021 (-7100 2760);
PAINT ORANGE (-7100 2760);
WIRE 16 -1 (-7125 2500)(-6000 2500);
FORCEPROP 0 LAST SIG_NAME RST_SYSTEM_BTN_N
J 0
(-7100 2510);
DISPLAY 0.617021 (-7100 2510);
PAINT ORANGE (-7100 2510);
WIRE 16 -1 (-7125 2400)(-6000 2400);
FORCEPROP 0 LAST SIG_NAME FP_NMI_BTN_N
J 0
(-7100 2410);
DISPLAY 0.617021 (-7100 2410);
PAINT ORANGE (-7100 2410);
WIRE 16 -1 (-7325 3850)(-6000 3850);
FORCEPROP 0 LAST SIG_NAME PU_IRQ_PCH_SCI_WHEA_N
J 0
(-7325 3861);
DISPLAY 0.617021 (-7325 3861);
PAINT ORANGE (-7325 3861);
WIRE 16 -1 (-7125 2300)(-6000 2300);
FORCEPROP 2 LAST SIG_NAME IRQ_PVDDQ_GHJ_VRHOT_LVT3_N
J 0
(-7100 2310);
DISPLAY 0.617021 (-7100 2310);
PAINT ORANGE (-7100 2310);
WIRE 16 -1 (-7125 2350)(-6000 2350);
FORCEPROP 2 LAST SIG_NAME IRQ_PVDDQ_KLM_VRHOT_LVT3_N
J 0
(-7100 2360);
DISPLAY 0.617021 (-7100 2360);
PAINT ORANGE (-7100 2360);
WIRE 16 -1 (-7125 2200)(-6000 2200);
FORCEPROP 2 LAST SIG_NAME IRQ_PVDDQ_ABC_VRHOT_LVT3_N
J 0
(-7100 2210);
DISPLAY 0.617021 (-7100 2210);
PAINT ORANGE (-7100 2210);
WIRE 16 -1 (-7125 2250)(-6000 2250);
FORCEPROP 2 LAST SIG_NAME IRQ_PVDDQ_DEF_VRHOT_LVT3_N
J 0
(-7100 2260);
DISPLAY 0.617021 (-7100 2260);
PAINT ORANGE (-7100 2260);
WIRE 16 -1 (-7325 3900)(-6000 3900);
FORCEPROP 0 LAST SIG_NAME FM_MB_SLOT_ID0
J 0
(-7325 3910);
DISPLAY 0.617021 (-7325 3910);
PAINT ORANGE (-7325 3910);
WIRE 16 -1 (-7325 3950)(-6000 3950);
FORCEPROP 0 LAST SIG_NAME FM_MB_SLOT_ID1
J 0
(-7325 3960);
DISPLAY 0.617021 (-7325 3960);
PAINT ORANGE (-7325 3960);
WIRE 16 -1 (-7325 3650)(-6000 3650);
FORCEPROP 0 LAST SIG_NAME PU_LPC_CLKRUN_N
J 0
(-7325 3661);
DISPLAY 0.617021 (-7325 3661);
PAINT ORANGE (-7325 3661);
WIRE 16 -1 (-7325 3750)(-6000 3750);
FORCEPROP 0 LAST SIG_NAME IRQ_VM_INT_N
J 0
(-7325 3760);
DISPLAY 0.617021 (-7325 3760);
PAINT ORANGE (-7325 3760);
WIRE 17 -1 (-7325 3475)(-7025 3475);
FORCEPROP 2 LAST SIG_NAME LPC_LAD_IO<3:0>
J 0
(-7325 3485);
DISPLAY 0.617021 (-7325 3485);
PAINT ORANGE (-7325 3485);
WIRE 17 -1 (-7025 3425)(-7025 3475);
WIRE 17 -1 (-7025 3375)(-7025 3425);
WIRE 17 -1 (-7025 3325)(-7025 3375);
WIRE 16 -1 (-7325 3700)(-6850 3700);
FORCEPROP 2 LAST SIG_NAME CLK_24M_BMC_LPC
J 0
(-7325 3710);
DISPLAY 0.617021 (-7325 3710);
PAINT ORANGE (-7325 3710);
DOT 1 (-2975 675);
DOT 1 (-2525 1150);
DOT 1 (-1700 4100);
FORCENOTE
ROOM=SB
(-7875 275) 0;
DISPLAY LEFT (-7875 275);
DISPLAY 1.021277 (-7875 275);
PAINT PURPLE (-7875 275);
QUIT
